FILE_TYPE = MACRO_DRAWING;
SET COLOR_WIRE YELLOW;
SET COLOR_PROP MONO;
SET COLOR_DOT WHITE;
SET COLOR_ARC YELLOW;
SET COLOR_BODY GREEN;
SET COLOR_NOTE MONO;
SET PROP_DISPLAY VALUE;
SET PAGE_NUMBER P118;
FORCEADD OFFPAGE..1
(-5775 3925);
FORCEPROP 2 LAST $XR0 55 
J 0
(-5996 3925);
DISPLAY 0.638298 (-5996 3925);
PAINT MONO (-5996 3925);
FORCEPROP 2 LAST $XR1 112 
J 0
(-6116 3925);
DISPLAY 0.638298 (-6116 3925);
PAINT MONO (-6116 3925);
FORCEPROP 2 LAST $XR2 144 
J 0
(-6236 3925);
DISPLAY 0.638298 (-6236 3925);
PAINT MONO (-6236 3925);
FORCEPROP 2 LAST $XR3 190 
J 0
(-6356 3925);
DISPLAY 0.638298 (-6356 3925);
PAINT MONO (-6356 3925);
FORCEPROP 1 LAST COMMENT_BODY TRUE
J 0
(-5650 3825);
DISPLAY 1.404255 (-5650 3825);
PAINT PEACH (-5650 3825);
DISPLAY INVISIBLE (-5650 3825);
FORCEPROP 2 LAST CDS_LIB mstr_standard
J 0
(-5775 3925);
PAINT MONO (-5775 3925);
DISPLAY INVISIBLE (-5775 3925);
FORCEPROP 2 LAST PATH I115
J 0
(-5725 4000);
DISPLAY 1.021277 (-5725 4000);
PAINT ORANGE (-5725 4000);
DISPLAY INVISIBLE (-5725 4000);
FORCEPROP 1 LAST OFFPAGE TRUE
J 0
(-5450 3800);
PAINT GREEN (-5450 3800);
DISPLAY INVISIBLE (-5450 3800);
FORCEADD P1V05_PCH_STBY_KR_PLL..1
(-1000 2025);
FORCEPROP 3 LASTPIN (-1000 1975) SIG_NAME P1V05_PCH_STBY_KR_PLL\g
J 0
(-990 1985);
DISPLAY 0.659574 (-990 1985);
PAINT MONO (-990 1985);
DISPLAY INVISIBLE (-990 1985);
FORCEPROP 1 LAST BODY_TYPE PLUMBING
J 0
(-1045 1982);
DISPLAY 0.340426 (-1045 1982);
PAINT GREEN (-1045 1982);
DISPLAY INVISIBLE (-1045 1982);
FORCEPROP 1 LAST VOLTAGE 1.05V
J 0
(-1045 1982);
DISPLAY 0.340426 (-1045 1982);
PAINT SKYBLUE (-1045 1982);
DISPLAY INVISIBLE (-1045 1982);
FORCEPROP 2 LAST CDS_LIB mstr_symbols
J 0
(-1000 2025);
PAINT ORANGE (-1000 2025);
DISPLAY INVISIBLE (-1000 2025);
FORCEPROP 1 LAST HDL_POWER P1V05_PCH_STBY_KR_PLL
J 1
(-1000 2075);
DISPLAY 0.872340 (-1000 2075);
PAINT GREEN (-1000 2075);
DISPLAY INVISIBLE (-1000 2075);
FORCEPROP 2 LAST ROOM SB_DECOUPLING
J 0
(-1000 2125);
DISPLAY 1.361702 (-1000 2125);
PAINT WHITE (-1000 2125);
DISPLAY INVISIBLE (-1000 2125);
FORCEPROP 1 LAST PATH I117
J 0
(-950 2050);
DISPLAY 0.872340 (-950 2050);
PAINT AQUA (-950 2050);
DISPLAY INVISIBLE (-950 2050);
FORCEPROP 2 LAST BOM_COST SB
J 0
(-1000 2175);
PAINT MONO (-1000 2175);
DISPLAY INVISIBLE (-1000 2175);
FORCEADD P1V05_PCH_STBY_KR_PLL..1
(-7225 2400);
FORCEPROP 3 LASTPIN (-7225 2350) SIG_NAME P1V05_PCH_STBY_KR_PLL\g
J 0
(-7215 2360);
DISPLAY 0.659574 (-7215 2360);
PAINT MONO (-7215 2360);
DISPLAY INVISIBLE (-7215 2360);
FORCEPROP 1 LAST HDL_POWER P1V05_PCH_STBY_KR_PLL
J 1
(-7225 2450);
DISPLAY 0.872340 (-7225 2450);
PAINT GREEN (-7225 2450);
DISPLAY INVISIBLE (-7225 2450);
FORCEPROP 2 LAST ROOM SB_DECOUPLING
J 0
(-7225 2500);
DISPLAY 1.361702 (-7225 2500);
PAINT WHITE (-7225 2500);
DISPLAY INVISIBLE (-7225 2500);
FORCEPROP 1 LAST PATH I118
J 0
(-7175 2425);
DISPLAY 0.872340 (-7175 2425);
PAINT AQUA (-7175 2425);
DISPLAY INVISIBLE (-7175 2425);
FORCEPROP 1 LAST BODY_TYPE PLUMBING
J 0
(-7270 2357);
DISPLAY 0.340426 (-7270 2357);
PAINT GREEN (-7270 2357);
DISPLAY INVISIBLE (-7270 2357);
FORCEPROP 2 LAST CDS_LIB mstr_symbols
J 0
(-7225 2400);
PAINT ORANGE (-7225 2400);
DISPLAY INVISIBLE (-7225 2400);
FORCEPROP 1 LAST VOLTAGE 1.05V
J 0
(-7270 2357);
DISPLAY 0.340426 (-7270 2357);
PAINT SKYBLUE (-7270 2357);
DISPLAY INVISIBLE (-7270 2357);
FORCEPROP 2 LAST BOM_COST SB
J 0
(-7225 2550);
PAINT MONO (-7225 2550);
DISPLAY INVISIBLE (-7225 2550);
FORCEADD OFFPAGE..5
(-5775 4225);
FORCEPROP 2 LAST $XR0 145 
J 0
(-6060 4225);
DISPLAY 0.638298 (-6060 4225);
PAINT MONO (-6060 4225);
FORCEPROP 2 LAST $XR1 169 
J 0
(-6180 4225);
DISPLAY 0.638298 (-6180 4225);
PAINT MONO (-6180 4225);
FORCEPROP 2 LAST CDS_LIB mstr_standard
J 0
(-5775 4225);
PAINT MONO (-5775 4225);
DISPLAY INVISIBLE (-5775 4225);
FORCEPROP 2 LAST PATH I119
J 0
(-5725 4300);
DISPLAY 1.021277 (-5725 4300);
PAINT ORANGE (-5725 4300);
DISPLAY INVISIBLE (-5725 4300);
FORCEPROP 1 LAST COMMENT_BODY TRUE
J 0
(-5675 4150);
DISPLAY 1.404255 (-5675 4150);
PAINT PEACH (-5675 4150);
DISPLAY INVISIBLE (-5675 4150);
FORCEPROP 1 LAST OFFPAGE TRUE
J 0
(-5450 4100);
PAINT GREEN (-5450 4100);
DISPLAY INVISIBLE (-5450 4100);
FORCEADD RES..1
(-1675 900);
FORCEPROP 1 LAST WATTAGE 1/16W
J 2
(-1675 800);
DISPLAY 0.617021 (-1675 800);
PAINT SKYBLUE (-1675 800);
FORCEPROP 1 LAST VALUE 0.0
J 2
(-1725 850);
DISPLAY 0.617021 (-1725 850);
PAINT SKYBLUE (-1725 850);
FORCEPROP 1 LASTPIN (-1775 900) $PN 1
J 0
(-1763 912);
DISPLAY 0.617021 (-1763 912);
PAINT ORANGE (-1763 912);
FORCEPROP 1 LAST MATERIAL CHIP
J 0
(-1675 800);
DISPLAY 0.617021 (-1675 800);
PAINT SKYBLUE (-1675 800);
FORCEPROP 1 LAST TOLERANCE 5%
J 0
(-1675 850);
DISPLAY 0.617021 (-1675 850);
PAINT SKYBLUE (-1675 850);
FORCEPROP 1 LAST LOCATION R8C24
J 0
(-1725 950);
DISPLAY 0.617021 (-1725 950);
PAINT AQUA (-1725 950);
FORCEPROP 1 LASTPIN (-1575 900) $PN 2
J 0
(-1613 912);
DISPLAY 0.617021 (-1613 912);
PAINT ORANGE (-1613 912);
FORCEPROP 1 LAST PACK_TYPE 0402
J 0
(-1600 850);
DISPLAY 0.617021 (-1600 850);
PAINT SKYBLUE (-1600 850);
FORCEPROP 1 LAST PART_NUMBER G21497-005
J 0
(-1575 800);
DISPLAY 0.617021 (-1575 800);
PAINT BLUE (-1575 800);
FORCEPROP 2 LAST CDS_LIB mstr_discrete
J 0
(-1675 900);
PAINT MONO (-1675 900);
DISPLAY INVISIBLE (-1675 900);
FORCEPROP 2 LAST CDS_LOCATION R8C24
J 0
(-1725 950);
DISPLAY 0.617021 (-1725 950);
PAINT AQUA (-1725 950);
DISPLAY INVISIBLE (-1725 950);
FORCEPROP 2 LAST ROOM SB
J 0
(-1725 1000);
DISPLAY 1.021277 (-1725 1000);
PAINT ORANGE (-1725 1000);
DISPLAY INVISIBLE (-1725 1000);
FORCEPROP 1 LAST PATH I120
J 0
(-1725 1050);
DISPLAY 0.978723 (-1725 1050);
PAINT WHITE (-1725 1050);
DISPLAY INVISIBLE (-1725 1050);
FORCEPROP 2 LAST BOM_COST SB
J 0
(-1725 1050);
DISPLAY 1.021277 (-1725 1050);
PAINT ORANGE (-1725 1050);
DISPLAY INVISIBLE (-1725 1050);
FORCEPROP 2 LAST SEC_TYPE 0402
J 0
(-1725 1100);
DISPLAY 1.021277 (-1725 1100);
PAINT ORANGE (-1725 1100);
DISPLAY INVISIBLE (-1725 1100);
FORCEPROP 2 LAST SEC 1
J 0
(-1725 1100);
DISPLAY 0.680851 (-1725 1100);
PAINT MONO (-1725 1100);
DISPLAY INVISIBLE (-1725 1100);
FORCEADD OFFPAGE..2
(-825 900);
FORCEPROP 2 LAST $XR0 139 
J 0
(-636 900);
DISPLAY 0.638298 (-636 900);
PAINT MONO (-636 900);
FORCEPROP 1 LAST COMMENT_BODY TRUE
J 0
(-870 805);
DISPLAY 1.170213 (-870 805);
PAINT PEACH (-870 805);
DISPLAY INVISIBLE (-870 805);
FORCEPROP 2 LAST CDS_LIB mstr_standard
J 0
(-825 900);
PAINT MONO (-825 900);
DISPLAY INVISIBLE (-825 900);
FORCEPROP 2 LAST PATH I122
J 0
(-650 975);
DISPLAY 1.021277 (-650 975);
PAINT ORANGE (-650 975);
DISPLAY INVISIBLE (-650 975);
FORCEPROP 1 LAST OFFPAGE TRUE
J 0
(-500 775);
DISPLAY 1.170213 (-500 775);
PAINT GREEN (-500 775);
DISPLAY INVISIBLE (-500 775);
FORCEADD OFFPAGE..2
(-825 675);
FORCEPROP 2 LAST $XR0 120 
J 0
(-636 675);
DISPLAY 0.638298 (-636 675);
PAINT MONO (-636 675);
FORCEPROP 2 LAST CDS_LIB mstr_standard
J 0
(-825 675);
PAINT MONO (-825 675);
DISPLAY INVISIBLE (-825 675);
FORCEPROP 1 LAST COMMENT_BODY TRUE
J 0
(-870 580);
DISPLAY 1.170213 (-870 580);
PAINT PEACH (-870 580);
DISPLAY INVISIBLE (-870 580);
FORCEPROP 2 LAST PATH I123
J 0
(-650 750);
DISPLAY 1.021277 (-650 750);
PAINT ORANGE (-650 750);
DISPLAY INVISIBLE (-650 750);
FORCEPROP 1 LAST OFFPAGE TRUE
J 0
(-500 550);
DISPLAY 1.170213 (-500 550);
PAINT GREEN (-500 550);
DISPLAY INVISIBLE (-500 550);
FORCEADD OFFPAGE..1
(-2900 900);
FORCEPROP 2 LAST $XR0 118 
J 0
(-3152 900);
DISPLAY 0.638298 (-3152 900);
PAINT MONO (-3152 900);
FORCEPROP 2 LAST PATH I124
J 0
(-2850 975);
DISPLAY 1.021277 (-2850 975);
PAINT ORANGE (-2850 975);
DISPLAY INVISIBLE (-2850 975);
FORCEPROP 2 LAST CDS_LIB mstr_standard
J 0
(-2900 900);
PAINT MONO (-2900 900);
DISPLAY INVISIBLE (-2900 900);
FORCEPROP 1 LAST COMMENT_BODY TRUE
J 0
(-2775 800);
DISPLAY 0.872340 (-2775 800);
PAINT GREEN (-2775 800);
DISPLAY INVISIBLE (-2775 800);
FORCEPROP 1 LAST OFFPAGE TRUE
J 0
(-2575 775);
DISPLAY 0.872340 (-2575 775);
PAINT GREEN (-2575 775);
DISPLAY INVISIBLE (-2575 775);
FORCEADD RES..1
(-1675 675);
FORCEPROP 1 LAST WATTAGE 1/16W
J 2
(-1700 525);
DISPLAY 0.617021 (-1700 525);
PAINT SKYBLUE (-1700 525);
FORCEPROP 1 LAST VALUE 0.0
J 2
(-1700 575);
DISPLAY 0.617021 (-1700 575);
PAINT SKYBLUE (-1700 575);
FORCEPROP 1 LASTPIN (-1775 675) $PN 1
J 0
(-1763 687);
DISPLAY 0.617021 (-1763 687);
PAINT ORANGE (-1763 687);
FORCEPROP 1 LAST TOLERANCE 5%
J 0
(-1675 575);
DISPLAY 0.617021 (-1675 575);
PAINT SKYBLUE (-1675 575);
FORCEPROP 1 LAST LOCATION R8C23
J 0
(-1725 725);
DISPLAY 0.617021 (-1725 725);
PAINT AQUA (-1725 725);
FORCEPROP 1 LASTPIN (-1575 675) $PN 2
J 0
(-1613 687);
DISPLAY 0.617021 (-1613 687);
PAINT ORANGE (-1613 687);
FORCEPROP 1 LAST PACK_TYPE 0402
J 0
(-1575 575);
DISPLAY 0.617021 (-1575 575);
PAINT SKYBLUE (-1575 575);
FORCEPROP 1 LAST PART_NUMBER G21497-005
J 0
(-1550 525);
DISPLAY 0.617021 (-1550 525);
PAINT BLUE (-1550 525);
FORCEPROP 1 LAST MATERIAL EMPTY
J 0
(-1675 525);
DISPLAY 0.617021 (-1675 525);
PAINT RED (-1675 525);
FORCEPROP 2 LAST CDS_LIB mstr_discrete
J 0
(-1675 675);
PAINT ORANGE (-1675 675);
DISPLAY INVISIBLE (-1675 675);
FORCEPROP 2 LAST CDS_LOCATION R8C23
J 0
(-1725 725);
DISPLAY 0.617021 (-1725 725);
PAINT AQUA (-1725 725);
DISPLAY INVISIBLE (-1725 725);
FORCEPROP 2 LAST SEC 1
J 0
(-1725 875);
DISPLAY 0.680851 (-1725 875);
PAINT MONO (-1725 875);
DISPLAY INVISIBLE (-1725 875);
FORCEPROP 2 LAST SEC_TYPE 0402
J 0
(-1725 875);
DISPLAY 1.021277 (-1725 875);
PAINT ORANGE (-1725 875);
DISPLAY INVISIBLE (-1725 875);
FORCEPROP 2 LAST BOM_COST SB
J 0
(-1725 825);
DISPLAY 1.021277 (-1725 825);
PAINT ORANGE (-1725 825);
DISPLAY INVISIBLE (-1725 825);
FORCEPROP 1 LAST PATH I125
J 0
(-1725 825);
DISPLAY 0.978723 (-1725 825);
PAINT WHITE (-1725 825);
DISPLAY INVISIBLE (-1725 825);
FORCEPROP 2 LAST ROOM SB
J 0
(-1725 775);
DISPLAY 1.021277 (-1725 775);
PAINT ORANGE (-1725 775);
DISPLAY INVISIBLE (-1725 775);
FORCEADD OFFPAGE..5
(-5775 4325);
FORCEPROP 2 LAST $XR0 145 
J 0
(-6060 4325);
DISPLAY 0.638298 (-6060 4325);
PAINT MONO (-6060 4325);
FORCEPROP 2 LAST $XR1 157 
J 0
(-6180 4325);
DISPLAY 0.638298 (-6180 4325);
PAINT MONO (-6180 4325);
FORCEPROP 2 LAST $XR2 190 
J 0
(-6300 4325);
DISPLAY 0.638298 (-6300 4325);
PAINT MONO (-6300 4325);
FORCEPROP 1 LAST COMMENT_BODY TRUE
J 0
(-5675 4250);
DISPLAY 1.404255 (-5675 4250);
PAINT PEACH (-5675 4250);
DISPLAY INVISIBLE (-5675 4250);
FORCEPROP 2 LAST CDS_LIB mstr_standard
J 0
(-5775 4325);
PAINT ORANGE (-5775 4325);
DISPLAY INVISIBLE (-5775 4325);
FORCEPROP 2 LAST PATH I126
J 0
(-5725 4400);
DISPLAY 1.021277 (-5725 4400);
PAINT ORANGE (-5725 4400);
DISPLAY INVISIBLE (-5725 4400);
FORCEPROP 1 LAST OFFPAGE TRUE
J 0
(-5450 4200);
PAINT GREEN (-5450 4200);
DISPLAY INVISIBLE (-5450 4200);
FORCEADD OFFPAGE..1
(-5775 4275);
FORCEPROP 2 LAST $XR0 199 
J 0
(-6057 4275);
DISPLAY 0.638298 (-6057 4275);
PAINT MONO (-6057 4275);
FORCEPROP 2 LAST $XR1 146 
J 0
(-6177 4275);
DISPLAY 0.638298 (-6177 4275);
PAINT MONO (-6177 4275);
FORCEPROP 2 LAST $XR2 170 
J 0
(-6297 4275);
DISPLAY 0.638298 (-6297 4275);
PAINT MONO (-6297 4275);
FORCEPROP 2 LAST CDS_LIB mstr_standard
J 0
(-5775 4275);
PAINT ORANGE (-5775 4275);
DISPLAY INVISIBLE (-5775 4275);
FORCEPROP 1 LAST COMMENT_BODY TRUE
J 0
(-5650 4175);
DISPLAY 1.404255 (-5650 4175);
PAINT PEACH (-5650 4175);
DISPLAY INVISIBLE (-5650 4175);
FORCEPROP 2 LAST PATH I127
J 0
(-5725 4350);
DISPLAY 1.021277 (-5725 4350);
PAINT ORANGE (-5725 4350);
DISPLAY INVISIBLE (-5725 4350);
FORCEPROP 1 LAST OFFPAGE TRUE
J 0
(-5450 4150);
PAINT GREEN (-5450 4150);
DISPLAY INVISIBLE (-5450 4150);
FORCEADD RES..2
(-2200 1100);
FORCEPROP 1 LASTPIN (-2200 1000) $PN 2
J 0
(-2195 1010);
DISPLAY 0.617021 (-2195 1010);
PAINT ORANGE (-2195 1010);
FORCEPROP 1 LASTPIN (-2200 1200) $PN 1
J 0
(-2195 1162);
DISPLAY 0.617021 (-2195 1162);
PAINT ORANGE (-2195 1162);
FORCEPROP 1 LAST TOLERANCE 1%
J 0
(-2155 1125);
DISPLAY 0.617021 (-2155 1125);
PAINT SKYBLUE (-2155 1125);
FORCEPROP 1 LAST WATTAGE 1/16W
J 0
(-2160 1075);
DISPLAY 0.617021 (-2160 1075);
PAINT SKYBLUE (-2160 1075);
FORCEPROP 1 LAST MATERIAL CHIP
J 0
(-2160 1025);
DISPLAY 0.617021 (-2160 1025);
PAINT SKYBLUE (-2160 1025);
FORCEPROP 1 LAST PACK_TYPE 0402
J 0
(-2160 925);
DISPLAY 0.617021 (-2160 925);
PAINT SKYBLUE (-2160 925);
FORCEPROP 1 LAST VALUE 10.0K
J 0
(-2155 1175);
DISPLAY 0.617021 (-2155 1175);
PAINT SKYBLUE (-2155 1175);
FORCEPROP 1 LAST PART_NUMBER G21796-016
J 0
(-2160 975);
DISPLAY 0.617021 (-2160 975);
PAINT BLUE (-2160 975);
FORCEPROP 1 LAST LOCATION R2N6
J 0
(-2155 1225);
DISPLAY 0.617021 (-2155 1225);
PAINT AQUA (-2155 1225);
FORCEPROP 2 LAST BOM_COST SB
J 0
(-2250 950);
PAINT MONO (-2250 950);
DISPLAY INVISIBLE (-2250 950);
FORCEPROP 2 LAST ROOM SB
J 0
(-2200 1100);
PAINT MONO (-2200 1100);
DISPLAY INVISIBLE (-2200 1100);
FORCEPROP 2 LAST CDS_LIB mstr_discrete
J 0
(-2200 1100);
PAINT MONO (-2200 1100);
DISPLAY INVISIBLE (-2200 1100);
FORCEPROP 2 LAST CDS_LOCATION R2N6
J 0
(-2155 1225);
DISPLAY 0.617021 (-2155 1225);
PAINT AQUA (-2155 1225);
DISPLAY INVISIBLE (-2155 1225);
FORCEPROP 1 LAST PATH I128
J 0
(-2150 1275);
DISPLAY 0.978723 (-2150 1275);
PAINT WHITE (-2150 1275);
DISPLAY INVISIBLE (-2150 1275);
FORCEPROP 2 LAST SEC_TYPE 0402
J 0
(-2150 1325);
DISPLAY 1.021277 (-2150 1325);
PAINT ORANGE (-2150 1325);
DISPLAY INVISIBLE (-2150 1325);
FORCEPROP 2 LAST SEC 1
J 0
(-2150 1325);
DISPLAY 0.680851 (-2150 1325);
PAINT MONO (-2150 1325);
DISPLAY INVISIBLE (-2150 1325);
FORCEADD P3V3_STBY..1
(-2200 1275);
FORCEPROP 3 LASTPIN (-2200 1225) SIG_NAME P3V3_STBY\g
J 0
(-2190 1235);
DISPLAY 0.659574 (-2190 1235);
PAINT MONO (-2190 1235);
DISPLAY INVISIBLE (-2190 1235);
FORCEPROP 1 LAST HDL_POWER P3V3_STBY
J 0
(-2500 1150);
DISPLAY 0.872340 (-2500 1150);
PAINT ORANGE (-2500 1150);
DISPLAY INVISIBLE (-2500 1150);
FORCEPROP 1 LAST VOLTAGE 3.3V
J 0
(-2245 1232);
DISPLAY 0.340426 (-2245 1232);
PAINT SKYBLUE (-2245 1232);
DISPLAY INVISIBLE (-2245 1232);
FORCEPROP 1 LAST BODY_TYPE PLUMBING
J 0
(-2245 1232);
DISPLAY 0.340426 (-2245 1232);
PAINT GREEN (-2245 1232);
DISPLAY INVISIBLE (-2245 1232);
FORCEPROP 1 LAST PATH I129
J 0
(-2155 1277);
DISPLAY 0.340426 (-2155 1277);
PAINT GREEN (-2155 1277);
DISPLAY INVISIBLE (-2155 1277);
FORCEPROP 2 LAST CDS_LIB mstr_symbols
J 0
(-2200 1275);
PAINT ORANGE (-2200 1275);
DISPLAY INVISIBLE (-2200 1275);
FORCEPROP 1 LAST SIZE 1B
J 0
(-2155 1297);
DISPLAY 0.340426 (-2155 1297);
PAINT GREEN (-2155 1297);
DISPLAY INVISIBLE (-2155 1297);
FORCEADD OFFPAGE..5
(-7375 3975);
FORCEPROP 2 LAST $XR0 135 
J 0
(-7660 3975);
DISPLAY 0.638298 (-7660 3975);
PAINT MONO (-7660 3975);
FORCEPROP 2 LAST $XR1 249 
J 0
(-7780 3975);
DISPLAY 0.638298 (-7780 3975);
PAINT MONO (-7780 3975);
FORCEPROP 2 LAST $XR2 145 
J 0
(-7900 3975);
DISPLAY 0.638298 (-7900 3975);
PAINT MONO (-7900 3975);
FORCEPROP 2 LAST $XR3 ?
J 0
(-7900 3975);
DISPLAY 0.638298 (-7900 3975);
PAINT MONO (-7900 3975);
FORCEPROP 2 LAST PATH I130
J 0
(-7325 4050);
DISPLAY 1.021277 (-7325 4050);
PAINT ORANGE (-7325 4050);
DISPLAY INVISIBLE (-7325 4050);
FORCEPROP 1 LAST COMMENT_BODY TRUE
J 0
(-7275 3900);
DISPLAY 1.404255 (-7275 3900);
PAINT PEACH (-7275 3900);
DISPLAY INVISIBLE (-7275 3900);
FORCEPROP 2 LAST CDS_LIB mstr_standard
J 0
(-7375 3975);
PAINT ORANGE (-7375 3975);
DISPLAY INVISIBLE (-7375 3975);
FORCEPROP 1 LAST OFFPAGE TRUE
J 0
(-7050 3850);
PAINT GREEN (-7050 3850);
DISPLAY INVISIBLE (-7050 3850);
FORCEADD RES..1
(-6750 3975);
FORCEPROP 1 LAST WATTAGE 1/16W
J 2
(-6900 3875);
DISPLAY 0.617021 (-6900 3875);
PAINT SKYBLUE (-6900 3875);
FORCEPROP 1 LAST VALUE 0.0
J 2
(-6800 3925);
DISPLAY 0.617021 (-6800 3925);
PAINT SKYBLUE (-6800 3925);
FORCEPROP 1 LASTPIN (-6850 3975) $PN 1
J 0
(-6838 3987);
DISPLAY 0.617021 (-6838 3987);
PAINT ORANGE (-6838 3987);
FORCEPROP 1 LAST MATERIAL CHIP
J 0
(-6900 3875);
DISPLAY 0.617021 (-6900 3875);
PAINT SKYBLUE (-6900 3875);
FORCEPROP 1 LASTPIN (-6650 3975) $PN 2
J 0
(-6688 3987);
DISPLAY 0.617021 (-6688 3987);
PAINT ORANGE (-6688 3987);
FORCEPROP 1 LAST TOLERANCE 5%
J 0
(-6750 3925);
DISPLAY 0.617021 (-6750 3925);
PAINT SKYBLUE (-6750 3925);
FORCEPROP 1 LAST LOCATION R7D23
J 0
(-6800 4025);
DISPLAY 0.617021 (-6800 4025);
PAINT AQUA (-6800 4025);
FORCEPROP 1 LAST PART_NUMBER G21497-005
J 0
(-6800 3875);
DISPLAY 0.617021 (-6800 3875);
PAINT BLUE (-6800 3875);
FORCEPROP 1 LAST PACK_TYPE 0402
J 0
(-6675 3925);
DISPLAY 0.617021 (-6675 3925);
PAINT SKYBLUE (-6675 3925);
FORCEPROP 2 LAST CDS_LOCATION R7D23
J 0
(-6800 4025);
DISPLAY 0.617021 (-6800 4025);
PAINT AQUA (-6800 4025);
DISPLAY INVISIBLE (-6800 4025);
FORCEPROP 2 LAST CDS_LIB mstr_discrete
J 0
(-6750 3975);
PAINT ORANGE (-6750 3975);
DISPLAY INVISIBLE (-6750 3975);
FORCEPROP 2 LAST ROOM SB
J 0
(-6800 4075);
DISPLAY 1.021277 (-6800 4075);
PAINT ORANGE (-6800 4075);
DISPLAY INVISIBLE (-6800 4075);
FORCEPROP 1 LAST PATH I131
J 0
(-6800 4125);
DISPLAY 0.978723 (-6800 4125);
PAINT WHITE (-6800 4125);
DISPLAY INVISIBLE (-6800 4125);
FORCEPROP 2 LAST BOM_COST SB
J 0
(-6800 4125);
DISPLAY 1.021277 (-6800 4125);
PAINT ORANGE (-6800 4125);
DISPLAY INVISIBLE (-6800 4125);
FORCEPROP 2 LAST SEC_TYPE 0402
J 0
(-6800 4175);
DISPLAY 1.021277 (-6800 4175);
PAINT ORANGE (-6800 4175);
DISPLAY INVISIBLE (-6800 4175);
FORCEPROP 2 LAST SEC 1
J 0
(-6800 4175);
DISPLAY 0.680851 (-6800 4175);
PAINT MONO (-6800 4175);
DISPLAY INVISIBLE (-6800 4175);
FORCEADD OFFPAGE..1
(-5775 4175);
FORCEPROP 2 LAST $XR0 21 
J 0
(-6026 4175);
DISPLAY 0.638298 (-6026 4175);
PAINT MONO (-6026 4175);
FORCEPROP 2 LAST $XR1 144 
J 0
(-6146 4175);
DISPLAY 0.638298 (-6146 4175);
PAINT MONO (-6146 4175);
FORCEPROP 2 LAST $XR2 190 
J 0
(-6266 4175);
DISPLAY 0.638298 (-6266 4175);
PAINT MONO (-6266 4175);
FORCEPROP 1 LAST OFFPAGE TRUE
J 0
(-5450 4050);
PAINT GREEN (-5450 4050);
DISPLAY INVISIBLE (-5450 4050);
FORCEPROP 1 LAST COMMENT_BODY TRUE
J 0
(-5650 4075);
DISPLAY 1.404255 (-5650 4075);
PAINT PEACH (-5650 4075);
DISPLAY INVISIBLE (-5650 4075);
FORCEPROP 2 LAST PATH I132
J 0
(-6025 4225);
DISPLAY 1.021277 (-6025 4225);
PAINT ORANGE (-6025 4225);
DISPLAY INVISIBLE (-6025 4225);
FORCEPROP 2 LAST CDS_LIB mstr_standard
J 0
(-5775 4175);
PAINT MONO (-5775 4175);
DISPLAY INVISIBLE (-5775 4175);
FORCEADD OFFPAGE..5
(-5775 3875);
FORCEPROP 2 LAST $XR0 118 
J 0
(-6060 3875);
DISPLAY 0.638298 (-6060 3875);
PAINT MONO (-6060 3875);
FORCEPROP 1 LAST COMMENT_BODY TRUE
J 0
(-5675 3800);
DISPLAY 1.404255 (-5675 3800);
PAINT PEACH (-5675 3800);
DISPLAY INVISIBLE (-5675 3800);
FORCEPROP 2 LAST CDS_LIB mstr_standard
J 0
(-5775 3875);
PAINT ORANGE (-5775 3875);
DISPLAY INVISIBLE (-5775 3875);
FORCEPROP 2 LAST PATH I133
J 0
(-5725 3950);
DISPLAY 1.021277 (-5725 3950);
PAINT ORANGE (-5725 3950);
DISPLAY INVISIBLE (-5725 3950);
FORCEPROP 1 LAST OFFPAGE TRUE
J 0
(-5450 3750);
PAINT GREEN (-5450 3750);
DISPLAY INVISIBLE (-5450 3750);
FORCEADD P3V3_STBY..1
(-5200 625);
FORCEPROP 3 LASTPIN (-5200 575) SIG_NAME P3V3_STBY\g
J 0
(-5190 585);
DISPLAY 0.659574 (-5190 585);
PAINT MONO (-5190 585);
DISPLAY INVISIBLE (-5190 585);
FORCEPROP 1 LAST HDL_POWER P3V3_STBY
J 0
(-5500 500);
DISPLAY 0.872340 (-5500 500);
PAINT ORANGE (-5500 500);
DISPLAY INVISIBLE (-5500 500);
FORCEPROP 1 LAST VOLTAGE 3.3V
J 0
(-5245 582);
DISPLAY 0.340426 (-5245 582);
PAINT SKYBLUE (-5245 582);
DISPLAY INVISIBLE (-5245 582);
FORCEPROP 1 LAST BODY_TYPE PLUMBING
J 0
(-5245 582);
DISPLAY 0.340426 (-5245 582);
PAINT GREEN (-5245 582);
DISPLAY INVISIBLE (-5245 582);
FORCEPROP 2 LAST CDS_LIB mstr_symbols
J 0
(-5200 625);
PAINT ORANGE (-5200 625);
DISPLAY INVISIBLE (-5200 625);
FORCEPROP 1 LAST PATH I135
J 0
(-5155 627);
DISPLAY 0.340426 (-5155 627);
PAINT GREEN (-5155 627);
DISPLAY INVISIBLE (-5155 627);
FORCEPROP 1 LAST SIZE 1B
J 0
(-5155 647);
DISPLAY 0.340426 (-5155 647);
PAINT GREEN (-5155 647);
DISPLAY INVISIBLE (-5155 647);
FORCEADD CAP_A..1
(-5200 375);
FORCEPROP 1 LASTPIN (-5200 275) $PN 2
J 0
(-5190 255);
DISPLAY 0.617021 (-5190 255);
PAINT ORANGE (-5190 255);
FORCEPROP 1 LASTPIN (-5200 475) $PN 1
J 0
(-5190 455);
DISPLAY 0.617021 (-5190 455);
PAINT ORANGE (-5190 455);
FORCEPROP 1 LAST MATERIAL X7R
J 0
(-5150 275);
DISPLAY 0.617021 (-5150 275);
PAINT SKYBLUE (-5150 275);
FORCEPROP 1 LAST VOLTAGE 16V
J 0
(-5150 375);
DISPLAY 0.617021 (-5150 375);
PAINT SKYBLUE (-5150 375);
FORCEPROP 1 LAST PACK_TYPE 0402V
J 0
(-5150 175);
DISPLAY 0.617021 (-5150 175);
PAINT SKYBLUE (-5150 175);
FORCEPROP 1 LAST TOLERANCE 10%
J 0
(-5150 325);
DISPLAY 0.617021 (-5150 325);
PAINT SKYBLUE (-5150 325);
FORCEPROP 1 LAST VALUE 0.1UF
J 0
(-5150 425);
DISPLAY 0.617021 (-5150 425);
PAINT SKYBLUE (-5150 425);
FORCEPROP 1 LAST PART_NUMBER A36096-030
J 0
(-5150 225);
DISPLAY 0.617021 (-5150 225);
PAINT BLUE (-5150 225);
FORCEPROP 1 LAST LOCATION C7D1
J 0
(-5150 475);
DISPLAY 0.617021 (-5150 475);
PAINT AQUA (-5150 475);
FORCEPROP 2 LAST CDS_LIB dev_discrete
J 0
(-5200 375);
PAINT ORANGE (-5200 375);
DISPLAY INVISIBLE (-5200 375);
FORCEPROP 2 LAST CDS_LOCATION C7D1
J 0
(-5150 475);
DISPLAY 0.617021 (-5150 475);
PAINT AQUA (-5150 475);
DISPLAY INVISIBLE (-5150 475);
FORCEPROP 2 LAST SEC_TYPE 0402V
J 0
(-5150 575);
DISPLAY 1.021277 (-5150 575);
PAINT ORANGE (-5150 575);
DISPLAY INVISIBLE (-5150 575);
FORCEPROP 2 LAST SEC 1
J 0
(-5150 575);
DISPLAY 0.680851 (-5150 575);
PAINT MONO (-5150 575);
DISPLAY INVISIBLE (-5150 575);
FORCEPROP 2 LAST CDS_SEC 1
J 0
(-5150 525);
PAINT ORANGE (-5150 525);
DISPLAY INVISIBLE (-5150 525);
FORCEPROP 2 LAST BOM_COST SB
J 0
(-5150 575);
DISPLAY 1.021277 (-5150 575);
PAINT ORANGE (-5150 575);
DISPLAY INVISIBLE (-5150 575);
FORCEPROP 2 LAST ROOM SB
J 0
(-5150 525);
DISPLAY 1.021277 (-5150 525);
PAINT ORANGE (-5150 525);
DISPLAY INVISIBLE (-5150 525);
FORCEPROP 1 LAST PATH I136
J 0
(-5150 525);
DISPLAY 0.978723 (-5150 525);
PAINT WHITE (-5150 525);
DISPLAY INVISIBLE (-5150 525);
FORCEADD GND..1
(-5200 125);
FORCEPROP 3 LASTPIN (-5200 175) SIG_NAME GND\g
J 0
(-5190 185);
DISPLAY 0.659574 (-5190 185);
PAINT MONO (-5190 185);
DISPLAY INVISIBLE (-5190 185);
FORCEPROP 1 LAST PATH I137
J 0
(-5125 125);
DISPLAY 0.872340 (-5125 125);
PAINT AQUA (-5125 125);
DISPLAY INVISIBLE (-5125 125);
FORCEPROP 1 LAST BODY_TYPE PLUMBING
J 0
(-5245 82);
DISPLAY 0.340426 (-5245 82);
PAINT GREEN (-5245 82);
DISPLAY INVISIBLE (-5245 82);
FORCEPROP 1 LAST SIZE 1B
J 0
(-5125 75);
DISPLAY 0.872340 (-5125 75);
PAINT AQUA (-5125 75);
DISPLAY INVISIBLE (-5125 75);
FORCEPROP 2 LAST CDS_LIB mstr_symbols
J 0
(-5200 125);
PAINT ORANGE (-5200 125);
DISPLAY INVISIBLE (-5200 125);
FORCEPROP 1 LAST VOLTAGE 0.0V
J 0
(-5245 82);
DISPLAY 0.340426 (-5245 82);
PAINT SKYBLUE (-5245 82);
DISPLAY INVISIBLE (-5245 82);
FORCEPROP 1 LAST HDL_POWER GND
J 0
(-5200 275);
DISPLAY 0.872340 (-5200 275);
PAINT GREEN (-5200 275);
DISPLAY INVISIBLE (-5200 275);
FORCEADD OFFPAGE..1
(-5800 1075);
FORCEPROP 2 LAST $XR0 118 
J 0
(-6052 1075);
DISPLAY 0.638298 (-6052 1075);
PAINT MONO (-6052 1075);
FORCEPROP 1 LAST COMMENT_BODY TRUE
J 0
(-5675 975);
DISPLAY 0.872340 (-5675 975);
PAINT GREEN (-5675 975);
DISPLAY INVISIBLE (-5675 975);
FORCEPROP 1 LAST OFFPAGE TRUE
J 0
(-5475 950);
DISPLAY 0.872340 (-5475 950);
PAINT GREEN (-5475 950);
DISPLAY INVISIBLE (-5475 950);
FORCEPROP 2 LAST CDS_LIB mstr_standard
J 0
(-5800 1075);
PAINT ORANGE (-5800 1075);
DISPLAY INVISIBLE (-5800 1075);
FORCEPROP 2 LAST PATH I138
J 0
(-5750 1150);
DISPLAY 1.021277 (-5750 1150);
PAINT ORANGE (-5750 1150);
DISPLAY INVISIBLE (-5750 1150);
FORCEADD OFFPAGE..2
(-3650 1075);
FORCEPROP 2 LAST $XR0 111 
J 0
(-3461 1075);
DISPLAY 0.638298 (-3461 1075);
PAINT MONO (-3461 1075);
FORCEPROP 2 LAST $XR1 22 
J 0
(-3341 1075);
DISPLAY 0.638298 (-3341 1075);
PAINT MONO (-3341 1075);
FORCEPROP 2 LAST $XR2 56 
J 0
(-3251 1075);
DISPLAY 0.638298 (-3251 1075);
PAINT MONO (-3251 1075);
FORCEPROP 1 LAST OFFPAGE TRUE
J 0
(-3325 950);
DISPLAY 1.170213 (-3325 950);
PAINT GREEN (-3325 950);
DISPLAY INVISIBLE (-3325 950);
FORCEPROP 1 LAST COMMENT_BODY TRUE
J 0
(-3695 980);
DISPLAY 1.170213 (-3695 980);
PAINT PEACH (-3695 980);
DISPLAY INVISIBLE (-3695 980);
FORCEPROP 2 LAST CDS_LIB mstr_standard
J 0
(-3650 1075);
PAINT ORANGE (-3650 1075);
DISPLAY INVISIBLE (-3650 1075);
FORCEPROP 2 LAST PATH I140
J 0
(-3475 1150);
DISPLAY 1.021277 (-3475 1150);
PAINT ORANGE (-3475 1150);
DISPLAY INVISIBLE (-3475 1150);
FORCEADD OFFPAGE..3
R 2
(-5675 2875);
FORCEPROP 2 LAST $XR0 111 
J 0
(-5955 2875);
DISPLAY 0.638298 (-5955 2875);
PAINT MONO (-5955 2875);
FORCEPROP 2 LAST $XR1 112 
J 0
(-6075 2875);
DISPLAY 0.638298 (-6075 2875);
PAINT MONO (-6075 2875);
FORCEPROP 1 LAST OFFPAGE TRUE
J 2
(-6000 2750);
DISPLAY 0.872340 (-6000 2750);
PAINT GREEN (-6000 2750);
DISPLAY INVISIBLE (-6000 2750);
FORCEPROP 2 LAST CDS_LIB mstr_standard
J 0
(-5675 2875);
PAINT ORANGE (-5675 2875);
DISPLAY INVISIBLE (-5675 2875);
FORCEPROP 1 LAST COMMENT_BODY TRUE
J 2
(-5625 2775);
DISPLAY 0.872340 (-5625 2775);
PAINT GREEN (-5625 2775);
DISPLAY INVISIBLE (-5625 2775);
FORCEPROP 2 LAST PATH I141
J 0
(-5625 2950);
DISPLAY 1.021277 (-5625 2950);
PAINT ORANGE (-5625 2950);
DISPLAY INVISIBLE (-5625 2950);
FORCEADD 74CBTLV1G125..1
(-4575 1075);
FORCEPROP 1 LAST PACK_TYPE SMLF
J 0
(-4725 820);
DISPLAY 0.617021 (-4725 820);
PAINT SKYBLUE (-4725 820);
FORCEPROP 1 LAST PART_NUMBER C88177-001
J 0
(-4740 935);
DISPLAY 0.617021 (-4740 935);
PAINT BLUE (-4740 935);
FORCEPROP 2 LASTPIN (-4825 1025) $PN 1
J 2
(-4835 1035);
DISPLAY 0.617021 (-4835 1035);
PAINT MONO (-4835 1035);
FORCEPROP 2 LASTPIN (-4825 1075) $PN 2
J 2
(-4835 1085);
DISPLAY 0.617021 (-4835 1085);
PAINT MONO (-4835 1085);
FORCEPROP 1 LAST MATERIAL IC
J 0
(-4775 1195);
DISPLAY 0.617021 (-4775 1195);
PAINT SKYBLUE (-4775 1195);
FORCEPROP 1 LAST LOCATION U7D1
J 0
(-4641 1206);
DISPLAY 0.617021 (-4641 1206);
PAINT AQUA (-4641 1206);
FORCEPROP 2 LASTPIN (-4325 1075) $PN 4
J 0
(-4315 1085);
DISPLAY 0.617021 (-4315 1085);
PAINT MONO (-4315 1085);
FORCEPROP 1 LAST POWER_GROUP VCC=P3V3_STBY;GND=GND;
J 0
(-4800 875);
DISPLAY 0.617021 (-4800 875);
PAINT ORANGE (-4800 875);
FORCEPROP 0 LAST ROOM DEBUG
J 0
(-4750 1400);
DISPLAY 1.021277 (-4750 1400);
PAINT ORANGE (-4750 1400);
DISPLAY INVISIBLE (-4750 1400);
FORCEPROP 0 LAST BOM_COST DEBUG
J 0
(-4750 1400);
DISPLAY 1.021277 (-4750 1400);
PAINT ORANGE (-4750 1400);
DISPLAY INVISIBLE (-4750 1400);
FORCEPROP 2 LAST CDS_LOCATION U7D1
J 0
(-4641 1206);
DISPLAY 0.617021 (-4641 1206);
PAINT AQUA (-4641 1206);
DISPLAY INVISIBLE (-4641 1206);
FORCEPROP 1 LAST PATH I142
J 0
(-4475 1195);
DISPLAY 0.872340 (-4475 1195);
PAINT PINK (-4475 1195);
DISPLAY INVISIBLE (-4475 1195);
FORCEPROP 2 LAST CDS_LIB mstr_ttl
J 0
(-4575 1075);
PAINT ORANGE (-4575 1075);
DISPLAY INVISIBLE (-4575 1075);
FORCEPROP 2 LAST CDS_SEC 1
J 0
(-4475 1250);
PAINT MONO (-4475 1250);
DISPLAY INVISIBLE (-4475 1250);
FORCEPROP 2 LAST $SEC 1
J 0
(-4475 1250);
PAINT MONO (-4475 1250);
DISPLAY INVISIBLE (-4475 1250);
FORCEADD RES..2
(-5175 1275);
FORCEPROP 1 LASTPIN (-5175 1175) $PN 2
J 0
(-5170 1185);
DISPLAY 0.617021 (-5170 1185);
PAINT ORANGE (-5170 1185);
FORCEPROP 1 LASTPIN (-5175 1375) $PN 1
J 0
(-5170 1337);
DISPLAY 0.617021 (-5170 1337);
PAINT ORANGE (-5170 1337);
FORCEPROP 1 LAST MATERIAL CHIP
J 0
(-5135 1200);
DISPLAY 0.617021 (-5135 1200);
PAINT SKYBLUE (-5135 1200);
FORCEPROP 1 LAST PACK_TYPE 0402
J 0
(-5135 1100);
DISPLAY 0.617021 (-5135 1100);
PAINT SKYBLUE (-5135 1100);
FORCEPROP 1 LAST TOLERANCE 1%
J 0
(-5130 1300);
DISPLAY 0.617021 (-5130 1300);
PAINT SKYBLUE (-5130 1300);
FORCEPROP 1 LAST VALUE 10.0K
J 0
(-5130 1350);
DISPLAY 0.617021 (-5130 1350);
PAINT SKYBLUE (-5130 1350);
FORCEPROP 1 LAST PART_NUMBER G21796-016
J 0
(-5135 1150);
DISPLAY 0.617021 (-5135 1150);
PAINT BLUE (-5135 1150);
FORCEPROP 1 LAST LOCATION R7C23
J 0
(-5130 1400);
DISPLAY 0.617021 (-5130 1400);
PAINT AQUA (-5130 1400);
FORCEPROP 1 LAST WATTAGE 1/16W
J 0
(-5135 1250);
DISPLAY 0.617021 (-5135 1250);
PAINT SKYBLUE (-5135 1250);
FORCEPROP 2 LAST BOM_COST SB
J 0
(-5225 1125);
PAINT MONO (-5225 1125);
DISPLAY INVISIBLE (-5225 1125);
FORCEPROP 2 LAST ROOM SB
J 0
(-5175 1275);
PAINT MONO (-5175 1275);
DISPLAY INVISIBLE (-5175 1275);
FORCEPROP 2 LAST CDS_LIB mstr_discrete
J 0
(-5175 1275);
PAINT ORANGE (-5175 1275);
DISPLAY INVISIBLE (-5175 1275);
FORCEPROP 2 LAST CDS_LOCATION R7C23
J 0
(-5130 1400);
DISPLAY 0.617021 (-5130 1400);
PAINT AQUA (-5130 1400);
DISPLAY INVISIBLE (-5130 1400);
FORCEPROP 1 LAST PATH I144
J 0
(-5125 1450);
DISPLAY 0.978723 (-5125 1450);
PAINT WHITE (-5125 1450);
DISPLAY INVISIBLE (-5125 1450);
FORCEPROP 2 LAST SEC 1
J 0
(-5125 1500);
DISPLAY 0.680851 (-5125 1500);
PAINT MONO (-5125 1500);
DISPLAY INVISIBLE (-5125 1500);
FORCEPROP 2 LAST SEC_TYPE 0402
J 0
(-5125 1500);
DISPLAY 1.021277 (-5125 1500);
PAINT ORANGE (-5125 1500);
DISPLAY INVISIBLE (-5125 1500);
FORCEADD P3V3_STBY..1
(-5175 1450);
FORCEPROP 3 LASTPIN (-5175 1400) SIG_NAME P3V3_STBY\g
J 0
(-5165 1410);
DISPLAY 0.659574 (-5165 1410);
PAINT MONO (-5165 1410);
DISPLAY INVISIBLE (-5165 1410);
FORCEPROP 1 LAST HDL_POWER P3V3_STBY
J 0
(-5475 1325);
DISPLAY 0.872340 (-5475 1325);
PAINT ORANGE (-5475 1325);
DISPLAY INVISIBLE (-5475 1325);
FORCEPROP 1 LAST BODY_TYPE PLUMBING
J 0
(-5220 1407);
DISPLAY 0.340426 (-5220 1407);
PAINT GREEN (-5220 1407);
DISPLAY INVISIBLE (-5220 1407);
FORCEPROP 1 LAST VOLTAGE 3.3V
J 0
(-5220 1407);
DISPLAY 0.340426 (-5220 1407);
PAINT SKYBLUE (-5220 1407);
DISPLAY INVISIBLE (-5220 1407);
FORCEPROP 1 LAST PATH I145
J 0
(-5130 1452);
DISPLAY 0.340426 (-5130 1452);
PAINT GREEN (-5130 1452);
DISPLAY INVISIBLE (-5130 1452);
FORCEPROP 1 LAST SIZE 1B
J 0
(-5130 1472);
DISPLAY 0.340426 (-5130 1472);
PAINT GREEN (-5130 1472);
DISPLAY INVISIBLE (-5130 1472);
FORCEPROP 2 LAST CDS_LIB mstr_symbols
J 0
(-5175 1450);
PAINT ORANGE (-5175 1450);
DISPLAY INVISIBLE (-5175 1450);
FORCEADD OFFPAGE..1
(-5650 2475);
FORCEPROP 2 LAST $XR0 188 
J 0
(-5932 2475);
DISPLAY 0.638298 (-5932 2475);
PAINT MONO (-5932 2475);
FORCEPROP 2 LAST CDS_LIB mstr_standard
J 0
(-5650 2475);
PAINT ORANGE (-5650 2475);
DISPLAY INVISIBLE (-5650 2475);
FORCEPROP 1 LAST COMMENT_BODY TRUE
J 0
(-5525 2375);
DISPLAY 1.404255 (-5525 2375);
PAINT PEACH (-5525 2375);
DISPLAY INVISIBLE (-5525 2375);
FORCEPROP 1 LAST OFFPAGE TRUE
J 0
(-5325 2350);
PAINT GREEN (-5325 2350);
DISPLAY INVISIBLE (-5325 2350);
FORCEPROP 2 LAST PATH I146
J 0
(-5600 2550);
DISPLAY 1.021277 (-5600 2550);
PAINT ORANGE (-5600 2550);
DISPLAY INVISIBLE (-5600 2550);
FORCEADD OFFPAGE..1
(-5650 2425);
FORCEPROP 2 LAST $XR0 188 
J 0
(-5932 2425);
DISPLAY 0.638298 (-5932 2425);
PAINT MONO (-5932 2425);
FORCEPROP 2 LAST CDS_LIB mstr_standard
J 0
(-5650 2425);
PAINT ORANGE (-5650 2425);
DISPLAY INVISIBLE (-5650 2425);
FORCEPROP 2 LAST PATH I147
J 0
(-5600 2500);
DISPLAY 1.021277 (-5600 2500);
PAINT ORANGE (-5600 2500);
DISPLAY INVISIBLE (-5600 2500);
FORCEPROP 1 LAST COMMENT_BODY TRUE
J 0
(-5525 2325);
DISPLAY 1.404255 (-5525 2325);
PAINT PEACH (-5525 2325);
DISPLAY INVISIBLE (-5525 2325);
FORCEPROP 1 LAST OFFPAGE TRUE
J 0
(-5325 2300);
PAINT GREEN (-5325 2300);
DISPLAY INVISIBLE (-5325 2300);
FORCEADD OFFPAGE..1
(-5650 2375);
FORCEPROP 2 LAST $XR0 188 
J 0
(-5932 2375);
DISPLAY 0.638298 (-5932 2375);
PAINT MONO (-5932 2375);
FORCEPROP 2 LAST CDS_LIB mstr_standard
J 0
(-5650 2375);
PAINT ORANGE (-5650 2375);
DISPLAY INVISIBLE (-5650 2375);
FORCEPROP 1 LAST COMMENT_BODY TRUE
J 0
(-5525 2275);
DISPLAY 1.404255 (-5525 2275);
PAINT PEACH (-5525 2275);
DISPLAY INVISIBLE (-5525 2275);
FORCEPROP 2 LAST PATH I148
J 0
(-5600 2450);
DISPLAY 1.021277 (-5600 2450);
PAINT ORANGE (-5600 2450);
DISPLAY INVISIBLE (-5600 2450);
FORCEPROP 1 LAST OFFPAGE TRUE
J 0
(-5325 2250);
PAINT GREEN (-5325 2250);
DISPLAY INVISIBLE (-5325 2250);
FORCEADD OFFPAGE..1
(-5650 2325);
FORCEPROP 2 LAST $XR0 188 
J 0
(-5932 2325);
DISPLAY 0.638298 (-5932 2325);
PAINT MONO (-5932 2325);
FORCEPROP 2 LAST CDS_LIB mstr_standard
J 0
(-5650 2325);
PAINT ORANGE (-5650 2325);
DISPLAY INVISIBLE (-5650 2325);
FORCEPROP 1 LAST COMMENT_BODY TRUE
J 0
(-5525 2225);
DISPLAY 1.404255 (-5525 2225);
PAINT PEACH (-5525 2225);
DISPLAY INVISIBLE (-5525 2225);
FORCEPROP 2 LAST PATH I149
J 0
(-5600 2400);
DISPLAY 1.021277 (-5600 2400);
PAINT ORANGE (-5600 2400);
DISPLAY INVISIBLE (-5600 2400);
FORCEPROP 1 LAST OFFPAGE TRUE
J 0
(-5325 2200);
PAINT GREEN (-5325 2200);
DISPLAY INVISIBLE (-5325 2200);
FORCEADD OFFPAGE..1
(-5650 2225);
FORCEPROP 2 LAST $XR0 188 
J 0
(-5932 2225);
DISPLAY 0.638298 (-5932 2225);
PAINT MONO (-5932 2225);
FORCEPROP 2 LAST CDS_LIB mstr_standard
J 0
(-5650 2225);
PAINT ORANGE (-5650 2225);
DISPLAY INVISIBLE (-5650 2225);
FORCEPROP 1 LAST COMMENT_BODY TRUE
J 0
(-5525 2125);
DISPLAY 1.404255 (-5525 2125);
PAINT PEACH (-5525 2125);
DISPLAY INVISIBLE (-5525 2125);
FORCEPROP 2 LAST PATH I150
J 0
(-5600 2300);
DISPLAY 1.021277 (-5600 2300);
PAINT ORANGE (-5600 2300);
DISPLAY INVISIBLE (-5600 2300);
FORCEPROP 1 LAST OFFPAGE TRUE
J 0
(-5325 2100);
PAINT GREEN (-5325 2100);
DISPLAY INVISIBLE (-5325 2100);
FORCEADD OFFPAGE..1
(-5650 2175);
FORCEPROP 2 LAST $XR0 188 
J 0
(-5932 2175);
DISPLAY 0.638298 (-5932 2175);
PAINT MONO (-5932 2175);
FORCEPROP 2 LAST CDS_LIB mstr_standard
J 0
(-5650 2175);
PAINT ORANGE (-5650 2175);
DISPLAY INVISIBLE (-5650 2175);
FORCEPROP 2 LAST PATH I151
J 0
(-5600 2250);
DISPLAY 1.021277 (-5600 2250);
PAINT ORANGE (-5600 2250);
DISPLAY INVISIBLE (-5600 2250);
FORCEPROP 1 LAST COMMENT_BODY TRUE
J 0
(-5525 2075);
DISPLAY 1.404255 (-5525 2075);
PAINT PEACH (-5525 2075);
DISPLAY INVISIBLE (-5525 2075);
FORCEPROP 1 LAST OFFPAGE TRUE
J 0
(-5325 2050);
PAINT GREEN (-5325 2050);
DISPLAY INVISIBLE (-5325 2050);
FORCEADD OFFPAGE..1
(-5650 2125);
FORCEPROP 2 LAST $XR0 188 
J 0
(-5932 2125);
DISPLAY 0.638298 (-5932 2125);
PAINT MONO (-5932 2125);
FORCEPROP 1 LAST OFFPAGE TRUE
J 0
(-5325 2000);
PAINT GREEN (-5325 2000);
DISPLAY INVISIBLE (-5325 2000);
FORCEPROP 1 LAST COMMENT_BODY TRUE
J 0
(-5525 2025);
DISPLAY 1.404255 (-5525 2025);
PAINT PEACH (-5525 2025);
DISPLAY INVISIBLE (-5525 2025);
FORCEPROP 2 LAST CDS_LIB mstr_standard
J 0
(-5650 2125);
PAINT ORANGE (-5650 2125);
DISPLAY INVISIBLE (-5650 2125);
FORCEPROP 2 LAST PATH I152
J 0
(-5600 2200);
DISPLAY 1.021277 (-5600 2200);
PAINT ORANGE (-5600 2200);
DISPLAY INVISIBLE (-5600 2200);
FORCEADD OFFPAGE..1
(-5650 2075);
FORCEPROP 2 LAST $XR0 188 
J 0
(-5932 2075);
DISPLAY 0.638298 (-5932 2075);
PAINT MONO (-5932 2075);
FORCEPROP 1 LAST COMMENT_BODY TRUE
J 0
(-5525 1975);
DISPLAY 1.404255 (-5525 1975);
PAINT PEACH (-5525 1975);
DISPLAY INVISIBLE (-5525 1975);
FORCEPROP 1 LAST OFFPAGE TRUE
J 0
(-5325 1950);
PAINT GREEN (-5325 1950);
DISPLAY INVISIBLE (-5325 1950);
FORCEPROP 2 LAST CDS_LIB mstr_standard
J 0
(-5650 2075);
PAINT ORANGE (-5650 2075);
DISPLAY INVISIBLE (-5650 2075);
FORCEPROP 2 LAST PATH I153
J 0
(-5600 2150);
DISPLAY 1.021277 (-5600 2150);
PAINT ORANGE (-5600 2150);
DISPLAY INVISIBLE (-5600 2150);
FORCEADD OFFPAGE..2
(-2525 2475);
FORCEPROP 2 LAST $XR0 188 
J 0
(-2336 2475);
DISPLAY 0.638298 (-2336 2475);
PAINT MONO (-2336 2475);
FORCEPROP 1 LAST COMMENT_BODY TRUE
J 0
(-2570 2380);
DISPLAY 1.404255 (-2570 2380);
PAINT PEACH (-2570 2380);
DISPLAY INVISIBLE (-2570 2380);
FORCEPROP 2 LAST CDS_LIB mstr_standard
J 0
(-2525 2475);
PAINT ORANGE (-2525 2475);
DISPLAY INVISIBLE (-2525 2475);
FORCEPROP 1 LAST OFFPAGE TRUE
J 0
(-2200 2350);
PAINT GREEN (-2200 2350);
DISPLAY INVISIBLE (-2200 2350);
FORCEPROP 2 LAST PATH I154
J 0
(-2350 2550);
DISPLAY 1.021277 (-2350 2550);
PAINT ORANGE (-2350 2550);
DISPLAY INVISIBLE (-2350 2550);
FORCEADD OFFPAGE..2
(-2525 2425);
FORCEPROP 2 LAST $XR0 188 
J 0
(-2336 2425);
DISPLAY 0.638298 (-2336 2425);
PAINT MONO (-2336 2425);
FORCEPROP 1 LAST COMMENT_BODY TRUE
J 0
(-2570 2330);
DISPLAY 1.404255 (-2570 2330);
PAINT PEACH (-2570 2330);
DISPLAY INVISIBLE (-2570 2330);
FORCEPROP 2 LAST CDS_LIB mstr_standard
J 0
(-2525 2425);
PAINT ORANGE (-2525 2425);
DISPLAY INVISIBLE (-2525 2425);
FORCEPROP 2 LAST PATH I155
J 0
(-2350 2500);
DISPLAY 1.021277 (-2350 2500);
PAINT ORANGE (-2350 2500);
DISPLAY INVISIBLE (-2350 2500);
FORCEPROP 1 LAST OFFPAGE TRUE
J 0
(-2200 2300);
PAINT GREEN (-2200 2300);
DISPLAY INVISIBLE (-2200 2300);
FORCEADD OFFPAGE..2
(-2525 2375);
FORCEPROP 2 LAST $XR0 188 
J 0
(-2336 2375);
DISPLAY 0.638298 (-2336 2375);
PAINT MONO (-2336 2375);
FORCEPROP 1 LAST COMMENT_BODY TRUE
J 0
(-2570 2280);
DISPLAY 1.404255 (-2570 2280);
PAINT PEACH (-2570 2280);
DISPLAY INVISIBLE (-2570 2280);
FORCEPROP 2 LAST CDS_LIB mstr_standard
J 0
(-2525 2375);
PAINT ORANGE (-2525 2375);
DISPLAY INVISIBLE (-2525 2375);
FORCEPROP 2 LAST PATH I156
J 0
(-2350 2450);
DISPLAY 1.021277 (-2350 2450);
PAINT ORANGE (-2350 2450);
DISPLAY INVISIBLE (-2350 2450);
FORCEPROP 1 LAST OFFPAGE TRUE
J 0
(-2200 2250);
PAINT GREEN (-2200 2250);
DISPLAY INVISIBLE (-2200 2250);
FORCEADD OFFPAGE..2
(-2525 2325);
FORCEPROP 2 LAST $XR0 188 
J 0
(-2336 2325);
DISPLAY 0.638298 (-2336 2325);
PAINT MONO (-2336 2325);
FORCEPROP 1 LAST COMMENT_BODY TRUE
J 0
(-2570 2230);
DISPLAY 1.404255 (-2570 2230);
PAINT PEACH (-2570 2230);
DISPLAY INVISIBLE (-2570 2230);
FORCEPROP 2 LAST CDS_LIB mstr_standard
J 0
(-2525 2325);
PAINT ORANGE (-2525 2325);
DISPLAY INVISIBLE (-2525 2325);
FORCEPROP 2 LAST PATH I157
J 0
(-2350 2400);
DISPLAY 1.021277 (-2350 2400);
PAINT ORANGE (-2350 2400);
DISPLAY INVISIBLE (-2350 2400);
FORCEPROP 1 LAST OFFPAGE TRUE
J 0
(-2200 2200);
PAINT GREEN (-2200 2200);
DISPLAY INVISIBLE (-2200 2200);
FORCEADD OFFPAGE..2
(-2525 2225);
FORCEPROP 2 LAST $XR0 188 
J 0
(-2336 2225);
DISPLAY 0.638298 (-2336 2225);
PAINT MONO (-2336 2225);
FORCEPROP 1 LAST COMMENT_BODY TRUE
J 0
(-2570 2130);
DISPLAY 1.404255 (-2570 2130);
PAINT PEACH (-2570 2130);
DISPLAY INVISIBLE (-2570 2130);
FORCEPROP 2 LAST CDS_LIB mstr_standard
J 0
(-2525 2225);
PAINT ORANGE (-2525 2225);
DISPLAY INVISIBLE (-2525 2225);
FORCEPROP 2 LAST PATH I158
J 0
(-2350 2300);
DISPLAY 1.021277 (-2350 2300);
PAINT ORANGE (-2350 2300);
DISPLAY INVISIBLE (-2350 2300);
FORCEPROP 1 LAST OFFPAGE TRUE
J 0
(-2200 2100);
PAINT GREEN (-2200 2100);
DISPLAY INVISIBLE (-2200 2100);
FORCEADD OFFPAGE..2
(-2525 2175);
FORCEPROP 2 LAST $XR0 188 
J 0
(-2336 2175);
DISPLAY 0.638298 (-2336 2175);
PAINT MONO (-2336 2175);
FORCEPROP 1 LAST COMMENT_BODY TRUE
J 0
(-2570 2080);
DISPLAY 1.404255 (-2570 2080);
PAINT PEACH (-2570 2080);
DISPLAY INVISIBLE (-2570 2080);
FORCEPROP 2 LAST CDS_LIB mstr_standard
J 0
(-2525 2175);
PAINT ORANGE (-2525 2175);
DISPLAY INVISIBLE (-2525 2175);
FORCEPROP 2 LAST PATH I159
J 0
(-2350 2250);
DISPLAY 1.021277 (-2350 2250);
PAINT ORANGE (-2350 2250);
DISPLAY INVISIBLE (-2350 2250);
FORCEPROP 1 LAST OFFPAGE TRUE
J 0
(-2200 2050);
PAINT GREEN (-2200 2050);
DISPLAY INVISIBLE (-2200 2050);
FORCEADD OFFPAGE..2
(-2525 2125);
FORCEPROP 2 LAST $XR0 188 
J 0
(-2336 2125);
DISPLAY 0.638298 (-2336 2125);
PAINT MONO (-2336 2125);
FORCEPROP 1 LAST OFFPAGE TRUE
J 0
(-2200 2000);
PAINT GREEN (-2200 2000);
DISPLAY INVISIBLE (-2200 2000);
FORCEPROP 1 LAST COMMENT_BODY TRUE
J 0
(-2570 2030);
DISPLAY 1.404255 (-2570 2030);
PAINT PEACH (-2570 2030);
DISPLAY INVISIBLE (-2570 2030);
FORCEPROP 2 LAST CDS_LIB mstr_standard
J 0
(-2525 2125);
PAINT ORANGE (-2525 2125);
DISPLAY INVISIBLE (-2525 2125);
FORCEPROP 2 LAST PATH I160
J 0
(-2350 2200);
DISPLAY 1.021277 (-2350 2200);
PAINT ORANGE (-2350 2200);
DISPLAY INVISIBLE (-2350 2200);
FORCEADD OFFPAGE..2
(-2525 2075);
FORCEPROP 2 LAST $XR0 188 
J 0
(-2336 2075);
DISPLAY 0.638298 (-2336 2075);
PAINT MONO (-2336 2075);
FORCEPROP 1 LAST COMMENT_BODY TRUE
J 0
(-2570 1980);
DISPLAY 1.404255 (-2570 1980);
PAINT PEACH (-2570 1980);
DISPLAY INVISIBLE (-2570 1980);
FORCEPROP 1 LAST OFFPAGE TRUE
J 0
(-2200 1950);
PAINT GREEN (-2200 1950);
DISPLAY INVISIBLE (-2200 1950);
FORCEPROP 2 LAST CDS_LIB mstr_standard
J 0
(-2525 2075);
PAINT ORANGE (-2525 2075);
DISPLAY INVISIBLE (-2525 2075);
FORCEPROP 2 LAST PATH I161
J 0
(-2350 2150);
DISPLAY 1.021277 (-2350 2150);
PAINT ORANGE (-2350 2150);
DISPLAY INVISIBLE (-2350 2150);
FORCEADD OFFPAGE..1
(-5800 1025);
FORCEPROP 2 LAST $XR0 211 
J 0
(-6052 1025);
DISPLAY 0.638298 (-6052 1025);
PAINT MONO (-6052 1025);
FORCEPROP 2 LAST $XR1 190 
J 0
(-6172 1025);
DISPLAY 0.638298 (-6172 1025);
PAINT MONO (-6172 1025);
FORCEPROP 1 LAST COMMENT_BODY TRUE
J 0
(-5675 925);
DISPLAY 0.872340 (-5675 925);
PAINT GREEN (-5675 925);
DISPLAY INVISIBLE (-5675 925);
FORCEPROP 1 LAST OFFPAGE TRUE
J 0
(-5475 900);
DISPLAY 0.872340 (-5475 900);
PAINT GREEN (-5475 900);
DISPLAY INVISIBLE (-5475 900);
FORCEPROP 2 LAST CDS_LIB mstr_standard
J 0
(-5800 1025);
PAINT ORANGE (-5800 1025);
DISPLAY INVISIBLE (-5800 1025);
FORCEPROP 2 LAST PATH I164
J 0
(-5750 1100);
DISPLAY 1.021277 (-5750 1100);
PAINT ORANGE (-5750 1100);
DISPLAY INVISIBLE (-5750 1100);
FORCEADD OFFPAGE..1
(-5775 4375);
FORCEPROP 2 LAST $XR0 22 
J 0
(-6026 4375);
DISPLAY 0.638298 (-6026 4375);
PAINT MONO (-6026 4375);
FORCEPROP 2 LAST $XR1 133 
J 0
(-6146 4375);
DISPLAY 0.638298 (-6146 4375);
PAINT MONO (-6146 4375);
FORCEPROP 2 LAST $XR2 120 
J 0
(-6266 4375);
DISPLAY 0.638298 (-6266 4375);
PAINT MONO (-6266 4375);
FORCEPROP 2 LAST $XR3 145 
J 0
(-6386 4375);
DISPLAY 0.638298 (-6386 4375);
PAINT MONO (-6386 4375);
FORCEPROP 1 LAST COMMENT_BODY TRUE
J 0
(-5650 4275);
DISPLAY 1.404255 (-5650 4275);
PAINT PEACH (-5650 4275);
DISPLAY INVISIBLE (-5650 4275);
FORCEPROP 2 LAST CDS_LIB mstr_standard
J 0
(-5775 4375);
PAINT ORANGE (-5775 4375);
DISPLAY INVISIBLE (-5775 4375);
FORCEPROP 2 LAST PATH I165
J 0
(-5725 4450);
DISPLAY 1.021277 (-5725 4450);
PAINT ORANGE (-5725 4450);
DISPLAY INVISIBLE (-5725 4450);
FORCEPROP 1 LAST OFFPAGE TRUE
J 0
(-5450 4250);
PAINT GREEN (-5450 4250);
DISPLAY INVISIBLE (-5450 4250);
FORCEADD OFFPAGE..5
(-5775 4425);
FORCEPROP 2 LAST $XR0 118 
J 0
(-6060 4425);
DISPLAY 0.638298 (-6060 4425);
PAINT MONO (-6060 4425);
FORCEPROP 1 LAST COMMENT_BODY TRUE
J 0
(-5675 4350);
DISPLAY 1.404255 (-5675 4350);
PAINT PEACH (-5675 4350);
DISPLAY INVISIBLE (-5675 4350);
FORCEPROP 2 LAST CDS_LIB mstr_standard
J 0
(-5775 4425);
PAINT ORANGE (-5775 4425);
DISPLAY INVISIBLE (-5775 4425);
FORCEPROP 2 LAST PATH I19
J 0
(-5725 4500);
DISPLAY 1.021277 (-5725 4500);
PAINT ORANGE (-5725 4500);
DISPLAY INVISIBLE (-5725 4500);
FORCEPROP 1 LAST OFFPAGE TRUE
J 0
(-5450 4300);
PAINT GREEN (-5450 4300);
DISPLAY INVISIBLE (-5450 4300);
FORCEADD OFFPAGE..5
(-5775 4125);
FORCEPROP 2 LAST $XR0 148 
J 0
(-6060 4125);
DISPLAY 0.638298 (-6060 4125);
PAINT MONO (-6060 4125);
FORCEPROP 2 LAST $XR1 191 
J 0
(-6180 4125);
DISPLAY 0.638298 (-6180 4125);
PAINT MONO (-6180 4125);
FORCEPROP 1 LAST OFFPAGE TRUE
J 0
(-5450 4000);
PAINT GREEN (-5450 4000);
DISPLAY INVISIBLE (-5450 4000);
FORCEPROP 1 LAST COMMENT_BODY TRUE
J 0
(-5675 4050);
DISPLAY 1.404255 (-5675 4050);
PAINT PEACH (-5675 4050);
DISPLAY INVISIBLE (-5675 4050);
FORCEPROP 2 LAST PATH I25
J 0
(-6025 4175);
DISPLAY 1.021277 (-6025 4175);
PAINT ORANGE (-6025 4175);
DISPLAY INVISIBLE (-6025 4175);
FORCEPROP 2 LAST CDS_LIB mstr_standard
J 0
(-5775 4125);
PAINT ORANGE (-5775 4125);
DISPLAY INVISIBLE (-5775 4125);
FORCEADD OFFPAGE..1
(-5775 4025);
FORCEPROP 2 LAST $XR0 156 
J 0
(-6057 4025);
DISPLAY 0.638298 (-6057 4025);
PAINT MONO (-6057 4025);
FORCEPROP 2 LAST $XR1 191 
J 0
(-6177 4025);
DISPLAY 0.638298 (-6177 4025);
PAINT MONO (-6177 4025);
FORCEPROP 2 LAST CDS_LIB mstr_standard
J 0
(-5775 4025);
PAINT ORANGE (-5775 4025);
DISPLAY INVISIBLE (-5775 4025);
FORCEPROP 1 LAST COMMENT_BODY TRUE
J 0
(-5650 3925);
DISPLAY 1.404255 (-5650 3925);
PAINT PEACH (-5650 3925);
DISPLAY INVISIBLE (-5650 3925);
FORCEPROP 1 LAST OFFPAGE TRUE
J 0
(-5450 3900);
PAINT GREEN (-5450 3900);
DISPLAY INVISIBLE (-5450 3900);
FORCEPROP 2 LAST PATH I26
J 0
(-5725 4100);
DISPLAY 1.021277 (-5725 4100);
PAINT ORANGE (-5725 4100);
DISPLAY INVISIBLE (-5725 4100);
FORCEADD OFFPAGE..5
(-5775 4075);
FORCEPROP 2 LAST $XR0 148 
J 0
(-6060 4075);
DISPLAY 0.638298 (-6060 4075);
PAINT MONO (-6060 4075);
FORCEPROP 2 LAST $XR1 190 
J 0
(-6180 4075);
DISPLAY 0.638298 (-6180 4075);
PAINT MONO (-6180 4075);
FORCEPROP 1 LAST COMMENT_BODY TRUE
J 0
(-5675 4000);
DISPLAY 1.404255 (-5675 4000);
PAINT PEACH (-5675 4000);
DISPLAY INVISIBLE (-5675 4000);
FORCEPROP 1 LAST OFFPAGE TRUE
J 0
(-5450 3950);
PAINT GREEN (-5450 3950);
DISPLAY INVISIBLE (-5450 3950);
FORCEPROP 2 LAST CDS_LIB mstr_standard
J 0
(-5775 4075);
PAINT ORANGE (-5775 4075);
DISPLAY INVISIBLE (-5775 4075);
FORCEPROP 2 LAST PATH I27
J 0
(-6025 4125);
DISPLAY 1.021277 (-6025 4125);
PAINT ORANGE (-6025 4125);
DISPLAY INVISIBLE (-6025 4125);
FORCEADD OFFPAGE..1
(-5675 3175);
FORCEPROP 2 LAST $XR0 111 
J 0
(-5957 3175);
DISPLAY 0.638298 (-5957 3175);
PAINT MONO (-5957 3175);
FORCEPROP 2 LAST $XR1 112 
J 0
(-6077 3175);
DISPLAY 0.638298 (-6077 3175);
PAINT MONO (-6077 3175);
FORCEPROP 1 LAST OFFPAGE TRUE
J 0
(-5350 3050);
PAINT GREEN (-5350 3050);
DISPLAY INVISIBLE (-5350 3050);
FORCEPROP 2 LAST PATH I34
J 0
(-5925 3225);
DISPLAY 1.021277 (-5925 3225);
PAINT ORANGE (-5925 3225);
DISPLAY INVISIBLE (-5925 3225);
FORCEPROP 2 LAST CDS_LIB mstr_standard
J 0
(-5675 3175);
PAINT ORANGE (-5675 3175);
DISPLAY INVISIBLE (-5675 3175);
FORCEPROP 1 LAST COMMENT_BODY TRUE
J 0
(-5550 3075);
DISPLAY 1.404255 (-5550 3075);
PAINT PEACH (-5550 3075);
DISPLAY INVISIBLE (-5550 3075);
FORCEADD OFFPAGE..6
(-5675 3125);
FORCEPROP 2 LAST $XR0 111 
J 0
(-5955 3125);
DISPLAY 0.638298 (-5955 3125);
PAINT MONO (-5955 3125);
FORCEPROP 2 LAST $XR1 112 
J 0
(-6075 3125);
DISPLAY 0.638298 (-6075 3125);
PAINT MONO (-6075 3125);
FORCEPROP 1 LAST OFFPAGE TRUE
J 0
(-5350 3000);
PAINT GREEN (-5350 3000);
DISPLAY INVISIBLE (-5350 3000);
FORCEPROP 1 LAST COMMENT_BODY TRUE
J 0
(-5575 3050);
DISPLAY 1.404255 (-5575 3050);
PAINT PEACH (-5575 3050);
DISPLAY INVISIBLE (-5575 3050);
FORCEPROP 2 LAST PATH I35
J 0
(-5950 3175);
DISPLAY 1.021277 (-5950 3175);
PAINT ORANGE (-5950 3175);
DISPLAY INVISIBLE (-5950 3175);
FORCEPROP 2 LAST CDS_LIB mstr_standard
J 0
(-5675 3125);
PAINT ORANGE (-5675 3125);
DISPLAY INVISIBLE (-5675 3125);
FORCEADD OFFPAGE..6
(-5675 3075);
FORCEPROP 2 LAST $XR0 112 
J 0
(-5955 3075);
DISPLAY 0.638298 (-5955 3075);
PAINT MONO (-5955 3075);
FORCEPROP 2 LAST $XR1 111 
J 0
(-6075 3075);
DISPLAY 0.638298 (-6075 3075);
PAINT MONO (-6075 3075);
FORCEPROP 1 LAST COMMENT_BODY TRUE
J 0
(-5575 3000);
DISPLAY 1.404255 (-5575 3000);
PAINT PEACH (-5575 3000);
DISPLAY INVISIBLE (-5575 3000);
FORCEPROP 1 LAST OFFPAGE TRUE
J 0
(-5350 2950);
PAINT GREEN (-5350 2950);
DISPLAY INVISIBLE (-5350 2950);
FORCEPROP 2 LAST PATH I36
J 0
(-5950 3125);
DISPLAY 1.021277 (-5950 3125);
PAINT ORANGE (-5950 3125);
DISPLAY INVISIBLE (-5950 3125);
FORCEPROP 2 LAST CDS_LIB mstr_standard
J 0
(-5675 3075);
PAINT ORANGE (-5675 3075);
DISPLAY INVISIBLE (-5675 3075);
FORCEADD OFFPAGE..6
(-5675 3025);
FORCEPROP 2 LAST $XR0 111 
J 0
(-5955 3025);
DISPLAY 0.638298 (-5955 3025);
PAINT MONO (-5955 3025);
FORCEPROP 2 LAST $XR1 112 
J 0
(-6075 3025);
DISPLAY 0.638298 (-6075 3025);
PAINT MONO (-6075 3025);
FORCEPROP 2 LAST CDS_LIB mstr_standard
J 0
(-5675 3025);
PAINT ORANGE (-5675 3025);
DISPLAY INVISIBLE (-5675 3025);
FORCEPROP 1 LAST COMMENT_BODY TRUE
J 0
(-5575 2950);
DISPLAY 1.404255 (-5575 2950);
PAINT PEACH (-5575 2950);
DISPLAY INVISIBLE (-5575 2950);
FORCEPROP 1 LAST OFFPAGE TRUE
J 0
(-5350 2900);
PAINT GREEN (-5350 2900);
DISPLAY INVISIBLE (-5350 2900);
FORCEPROP 2 LAST PATH I37
J 0
(-5950 3075);
DISPLAY 1.021277 (-5950 3075);
PAINT ORANGE (-5950 3075);
DISPLAY INVISIBLE (-5950 3075);
FORCEADD OFFPAGE..5
(-5700 2975);
FORCEPROP 2 LAST $XR0 111 
J 0
(-5955 2975);
DISPLAY 0.638298 (-5955 2975);
PAINT MONO (-5955 2975);
FORCEPROP 2 LAST $XR1 112 
J 0
(-6075 2975);
DISPLAY 0.638298 (-6075 2975);
PAINT MONO (-6075 2975);
FORCEPROP 2 LAST PATH I38
J 0
(-5975 3025);
DISPLAY 1.021277 (-5975 3025);
PAINT ORANGE (-5975 3025);
DISPLAY INVISIBLE (-5975 3025);
FORCEPROP 2 LAST CDS_LIB mstr_standard
J 0
(-5700 2975);
PAINT ORANGE (-5700 2975);
DISPLAY INVISIBLE (-5700 2975);
FORCEPROP 1 LAST COMMENT_BODY TRUE
J 0
(-5600 2900);
DISPLAY 1.404255 (-5600 2900);
PAINT PEACH (-5600 2900);
DISPLAY INVISIBLE (-5600 2900);
FORCEPROP 1 LAST OFFPAGE TRUE
J 0
(-5375 2850);
PAINT GREEN (-5375 2850);
DISPLAY INVISIBLE (-5375 2850);
FORCEADD OFFPAGE..3
R 2
(-5675 2825);
FORCEPROP 2 LAST $XR0 112 
J 0
(-5955 2825);
DISPLAY 0.638298 (-5955 2825);
PAINT MONO (-5955 2825);
FORCEPROP 2 LAST $XR1 111 
J 0
(-6075 2825);
DISPLAY 0.638298 (-6075 2825);
PAINT MONO (-6075 2825);
FORCEPROP 1 LAST OFFPAGE TRUE
J 2
(-6000 2700);
DISPLAY 0.872340 (-6000 2700);
PAINT GREEN (-6000 2700);
DISPLAY INVISIBLE (-6000 2700);
FORCEPROP 2 LAST CDS_LIB mstr_standard
J 2
(-5675 2825);
PAINT ORANGE (-5675 2825);
DISPLAY INVISIBLE (-5675 2825);
FORCEPROP 1 LAST COMMENT_BODY TRUE
J 2
(-5625 2725);
DISPLAY 0.872340 (-5625 2725);
PAINT GREEN (-5625 2725);
DISPLAY INVISIBLE (-5625 2725);
FORCEPROP 2 LAST PATH I40
J 2
(-5425 2875);
DISPLAY 1.021277 (-5425 2875);
PAINT ORANGE (-5425 2875);
DISPLAY INVISIBLE (-5425 2875);
FORCEADD OFFPAGE..4
(-1925 4175);
FORCEPROP 2 LAST $XR0 142 
J 0
(-1739 4175);
DISPLAY 0.638298 (-1739 4175);
PAINT MONO (-1739 4175);
FORCEPROP 1 LAST OFFPAGE TRUE
J 0
(-1600 4050);
PAINT GREEN (-1600 4050);
DISPLAY INVISIBLE (-1600 4050);
FORCEPROP 1 LAST COMMENT_BODY TRUE
J 0
(-1950 4075);
DISPLAY 1.404255 (-1950 4075);
PAINT PEACH (-1950 4075);
DISPLAY INVISIBLE (-1950 4075);
FORCEPROP 2 LAST CDS_LIB mstr_standard
J 0
(-1925 4175);
PAINT ORANGE (-1925 4175);
DISPLAY INVISIBLE (-1925 4175);
FORCEPROP 2 LAST PATH I41
J 0
(-1750 4250);
DISPLAY 1.021277 (-1750 4250);
PAINT ORANGE (-1750 4250);
DISPLAY INVISIBLE (-1750 4250);
FORCEADD OFFPAGE..2
(-1925 4125);
FORCEPROP 2 LAST $XR0 191 
J 0
(-1736 4125);
DISPLAY 0.638298 (-1736 4125);
PAINT MONO (-1736 4125);
FORCEPROP 1 LAST COMMENT_BODY TRUE
J 0
(-1970 4030);
DISPLAY 1.404255 (-1970 4030);
PAINT PEACH (-1970 4030);
DISPLAY INVISIBLE (-1970 4030);
FORCEPROP 1 LAST OFFPAGE TRUE
J 0
(-1600 4000);
PAINT GREEN (-1600 4000);
DISPLAY INVISIBLE (-1600 4000);
FORCEPROP 2 LAST CDS_LIB mstr_standard
J 0
(-1925 4125);
PAINT ORANGE (-1925 4125);
DISPLAY INVISIBLE (-1925 4125);
FORCEPROP 2 LAST PATH I42
J 0
(-1750 4200);
DISPLAY 1.021277 (-1750 4200);
PAINT ORANGE (-1750 4200);
DISPLAY INVISIBLE (-1750 4200);
FORCEADD OFFPAGE..4
(-1925 4025);
FORCEPROP 2 LAST $XR0 190 
J 0
(-1739 4025);
DISPLAY 0.638298 (-1739 4025);
PAINT MONO (-1739 4025);
FORCEPROP 2 LAST $XR1 192 
J 0
(-1619 4025);
DISPLAY 0.638298 (-1619 4025);
PAINT MONO (-1619 4025);
FORCEPROP 2 LAST $XR2 111 
J 0
(-1499 4025);
DISPLAY 0.638298 (-1499 4025);
PAINT MONO (-1499 4025);
FORCEPROP 1 LAST COMMENT_BODY TRUE
J 0
(-1950 3925);
DISPLAY 1.404255 (-1950 3925);
PAINT PEACH (-1950 3925);
DISPLAY INVISIBLE (-1950 3925);
FORCEPROP 2 LAST CDS_LIB mstr_standard
J 0
(-1925 4025);
PAINT ORANGE (-1925 4025);
DISPLAY INVISIBLE (-1925 4025);
FORCEPROP 1 LAST OFFPAGE TRUE
J 0
(-1600 3900);
PAINT GREEN (-1600 3900);
DISPLAY INVISIBLE (-1600 3900);
FORCEPROP 2 LAST PATH I44
J 0
(-1600 4075);
DISPLAY 1.021277 (-1600 4075);
PAINT ORANGE (-1600 4075);
DISPLAY INVISIBLE (-1600 4075);
FORCEADD OFFPAGE..4
(-1925 3875);
FORCEPROP 2 LAST $XR0 156 
J 0
(-1739 3875);
DISPLAY 0.638298 (-1739 3875);
PAINT MONO (-1739 3875);
FORCEPROP 2 LAST $XR1 191 
J 0
(-1619 3875);
DISPLAY 0.638298 (-1619 3875);
PAINT MONO (-1619 3875);
FORCEPROP 1 LAST COMMENT_BODY TRUE
J 0
(-1950 3775);
DISPLAY 0.872340 (-1950 3775);
PAINT GREEN (-1950 3775);
DISPLAY INVISIBLE (-1950 3775);
FORCEPROP 2 LAST CDS_LIB mstr_standard
J 0
(-1925 3875);
PAINT ORANGE (-1925 3875);
DISPLAY INVISIBLE (-1925 3875);
FORCEPROP 2 LAST PATH I46
J 0
(-1750 3950);
DISPLAY 1.021277 (-1750 3950);
PAINT ORANGE (-1750 3950);
DISPLAY INVISIBLE (-1750 3950);
FORCEPROP 1 LAST OFFPAGE TRUE
J 0
(-1600 3750);
DISPLAY 0.872340 (-1600 3750);
PAINT GREEN (-1600 3750);
DISPLAY INVISIBLE (-1600 3750);
FORCEADD OFFPAGE..4
(-1925 4275);
FORCEPROP 2 LAST $XR0 133 
J 0
(-1739 4275);
DISPLAY 0.638298 (-1739 4275);
PAINT MONO (-1739 4275);
FORCEPROP 2 LAST $XR1 191 
J 0
(-1619 4275);
DISPLAY 0.638298 (-1619 4275);
PAINT MONO (-1619 4275);
FORCEPROP 2 LAST $XR2 144 
J 0
(-1499 4275);
DISPLAY 0.638298 (-1499 4275);
PAINT MONO (-1499 4275);
FORCEPROP 1 LAST COMMENT_BODY TRUE
J 0
(-1950 4175);
DISPLAY 1.404255 (-1950 4175);
PAINT PEACH (-1950 4175);
DISPLAY INVISIBLE (-1950 4175);
FORCEPROP 2 LAST CDS_LIB mstr_standard
J 0
(-1925 4275);
PAINT ORANGE (-1925 4275);
DISPLAY INVISIBLE (-1925 4275);
FORCEPROP 1 LAST OFFPAGE TRUE
J 0
(-1600 4150);
PAINT GREEN (-1600 4150);
DISPLAY INVISIBLE (-1600 4150);
FORCEPROP 2 LAST PATH I47
J 0
(-1375 4325);
DISPLAY 1.021277 (-1375 4325);
PAINT ORANGE (-1375 4325);
DISPLAY INVISIBLE (-1375 4325);
FORCEADD OFFPAGE..2
(-1925 4425);
FORCEPROP 2 LAST $XR0 92 
J 0
(-1736 4425);
DISPLAY 0.638298 (-1736 4425);
PAINT MONO (-1736 4425);
FORCEPROP 1 LAST COMMENT_BODY TRUE
J 0
(-1970 4330);
DISPLAY 1.404255 (-1970 4330);
PAINT PEACH (-1970 4330);
DISPLAY INVISIBLE (-1970 4330);
FORCEPROP 2 LAST CDS_LIB mstr_standard
J 0
(-1925 4425);
PAINT ORANGE (-1925 4425);
DISPLAY INVISIBLE (-1925 4425);
FORCEPROP 1 LAST OFFPAGE TRUE
J 0
(-1600 4300);
PAINT GREEN (-1600 4300);
DISPLAY INVISIBLE (-1600 4300);
FORCEPROP 2 LAST PATH I48
J 0
(-1750 4500);
DISPLAY 1.021277 (-1750 4500);
PAINT ORANGE (-1750 4500);
DISPLAY INVISIBLE (-1750 4500);
FORCEADD OFFPAGE..4
(-1925 4375);
FORCEPROP 2 LAST $XR0 196 
J 0
(-1739 4375);
DISPLAY 0.638298 (-1739 4375);
PAINT MONO (-1739 4375);
FORCEPROP 2 LAST $XR1 200 
J 0
(-1619 4375);
DISPLAY 0.638298 (-1619 4375);
PAINT MONO (-1619 4375);
FORCEPROP 2 LAST $XR2 157 
J 0
(-1499 4375);
DISPLAY 0.638298 (-1499 4375);
PAINT MONO (-1499 4375);
FORCEPROP 2 LAST $XR3 183 
J 0
(-1379 4375);
DISPLAY 0.638298 (-1379 4375);
PAINT MONO (-1379 4375);
FORCEPROP 2 LAST $XR4 191 
J 0
(-1259 4375);
DISPLAY 0.638298 (-1259 4375);
PAINT MONO (-1259 4375);
FORCEPROP 1 LAST COMMENT_BODY TRUE
J 0
(-1950 4275);
DISPLAY 1.404255 (-1950 4275);
PAINT PEACH (-1950 4275);
DISPLAY INVISIBLE (-1950 4275);
FORCEPROP 2 LAST CDS_LIB mstr_standard
J 0
(-1925 4375);
PAINT ORANGE (-1925 4375);
DISPLAY INVISIBLE (-1925 4375);
FORCEPROP 1 LAST OFFPAGE TRUE
J 0
(-1600 4250);
PAINT GREEN (-1600 4250);
DISPLAY INVISIBLE (-1600 4250);
FORCEPROP 2 LAST PATH I49
J 0
(-1750 4450);
DISPLAY 1.021277 (-1750 4450);
PAINT ORANGE (-1750 4450);
DISPLAY INVISIBLE (-1750 4450);
FORCEADD OFFPAGE..4
(-1925 4325);
FORCEPROP 2 LAST $XR0 133 
J 0
(-1739 4325);
DISPLAY 0.638298 (-1739 4325);
PAINT MONO (-1739 4325);
FORCEPROP 2 LAST $XR1 191 
J 0
(-1619 4325);
DISPLAY 0.638298 (-1619 4325);
PAINT MONO (-1619 4325);
FORCEPROP 2 LAST $XR2 144 
J 0
(-1499 4325);
DISPLAY 0.638298 (-1499 4325);
PAINT MONO (-1499 4325);
FORCEPROP 1 LAST COMMENT_BODY TRUE
J 0
(-1950 4225);
DISPLAY 1.404255 (-1950 4225);
PAINT PEACH (-1950 4225);
DISPLAY INVISIBLE (-1950 4225);
FORCEPROP 2 LAST CDS_LIB mstr_standard
J 0
(-1925 4325);
PAINT ORANGE (-1925 4325);
DISPLAY INVISIBLE (-1925 4325);
FORCEPROP 1 LAST OFFPAGE TRUE
J 0
(-1600 4200);
PAINT GREEN (-1600 4200);
DISPLAY INVISIBLE (-1600 4200);
FORCEPROP 2 LAST PATH I50
J 0
(-1250 4375);
DISPLAY 1.021277 (-1250 4375);
PAINT ORANGE (-1250 4375);
DISPLAY INVISIBLE (-1250 4375);
FORCEADD OFFPAGE..4
(-1925 2825);
FORCEPROP 2 LAST $XR0 134 
J 0
(-1739 2825);
DISPLAY 0.638298 (-1739 2825);
PAINT MONO (-1739 2825);
FORCEPROP 1 LAST COMMENT_BODY TRUE
J 0
(-1950 2725);
DISPLAY 1.404255 (-1950 2725);
PAINT PEACH (-1950 2725);
DISPLAY INVISIBLE (-1950 2725);
FORCEPROP 2 LAST CDS_LIB mstr_standard
J 0
(-1925 2825);
PAINT ORANGE (-1925 2825);
DISPLAY INVISIBLE (-1925 2825);
FORCEPROP 1 LAST OFFPAGE TRUE
J 0
(-1600 2700);
PAINT GREEN (-1600 2700);
DISPLAY INVISIBLE (-1600 2700);
FORCEPROP 2 LAST PATH I53
J 0
(-1725 2875);
DISPLAY 1.021277 (-1725 2875);
PAINT ORANGE (-1725 2875);
DISPLAY INVISIBLE (-1725 2875);
FORCEADD OFFPAGE..2
(-1925 2775);
FORCEPROP 2 LAST $XR0 166 
J 0
(-1736 2775);
DISPLAY 0.638298 (-1736 2775);
PAINT MONO (-1736 2775);
FORCEPROP 1 LAST COMMENT_BODY TRUE
J 0
(-1970 2680);
DISPLAY 1.404255 (-1970 2680);
PAINT PEACH (-1970 2680);
DISPLAY INVISIBLE (-1970 2680);
FORCEPROP 2 LAST CDS_LIB mstr_standard
J 0
(-1925 2775);
PAINT ORANGE (-1925 2775);
DISPLAY INVISIBLE (-1925 2775);
FORCEPROP 1 LAST OFFPAGE TRUE
J 0
(-1600 2650);
PAINT GREEN (-1600 2650);
DISPLAY INVISIBLE (-1600 2650);
FORCEPROP 2 LAST PATH I54
J 0
(-1725 2825);
DISPLAY 1.021277 (-1725 2825);
PAINT ORANGE (-1725 2825);
DISPLAY INVISIBLE (-1725 2825);
FORCEADD OFFPAGE..5
(-5675 2725);
FORCEPROP 2 LAST $XR0 111 
J 0
(-5930 2725);
DISPLAY 0.638298 (-5930 2725);
PAINT MONO (-5930 2725);
FORCEPROP 2 LAST CDS_LIB mstr_standard
J 0
(-5675 2725);
PAINT ORANGE (-5675 2725);
DISPLAY INVISIBLE (-5675 2725);
FORCEPROP 1 LAST COMMENT_BODY TRUE
J 0
(-5575 2650);
DISPLAY 1.404255 (-5575 2650);
PAINT PEACH (-5575 2650);
DISPLAY INVISIBLE (-5575 2650);
FORCEPROP 2 LAST PATH I55
J 0
(-5625 2800);
DISPLAY 1.021277 (-5625 2800);
PAINT ORANGE (-5625 2800);
DISPLAY INVISIBLE (-5625 2800);
FORCEPROP 1 LAST OFFPAGE TRUE
J 0
(-5350 2600);
PAINT GREEN (-5350 2600);
DISPLAY INVISIBLE (-5350 2600);
FORCEADD OFFPAGE..2
R 2
(-5675 2675);
FORCEPROP 2 LAST $XR0 111 
J 0
(-5930 2675);
DISPLAY 0.638298 (-5930 2675);
PAINT MONO (-5930 2675);
FORCEPROP 2 LAST $XR1 112 
J 0
(-6050 2675);
DISPLAY 0.638298 (-6050 2675);
PAINT MONO (-6050 2675);
FORCEPROP 1 LAST OFFPAGE TRUE
J 2
(-6000 2550);
DISPLAY 0.872340 (-6000 2550);
PAINT GREEN (-6000 2550);
DISPLAY INVISIBLE (-6000 2550);
FORCEPROP 2 LAST PATH I56
J 2
(-5725 2750);
DISPLAY 1.021277 (-5725 2750);
PAINT ORANGE (-5725 2750);
DISPLAY INVISIBLE (-5725 2750);
FORCEPROP 2 LAST CDS_LIB mstr_standard
J 2
(-5675 2675);
PAINT ORANGE (-5675 2675);
DISPLAY INVISIBLE (-5675 2675);
FORCEPROP 1 LAST COMMENT_BODY TRUE
J 2
(-5630 2580);
DISPLAY 0.872340 (-5630 2580);
PAINT GREEN (-5630 2580);
DISPLAY INVISIBLE (-5630 2580);
FORCEADD RES..1
(-1575 2675);
FORCEPROP 1 LAST VALUE 10.0
J 2
(-1600 2625);
DISPLAY 0.617021 (-1600 2625);
PAINT SKYBLUE (-1600 2625);
FORCEPROP 1 LAST WATTAGE 1/16W
J 2
(-1575 2575);
DISPLAY 0.617021 (-1575 2575);
PAINT SKYBLUE (-1575 2575);
FORCEPROP 1 LASTPIN (-1675 2675) $PN 1
J 0
(-1663 2687);
DISPLAY 0.617021 (-1663 2687);
PAINT ORANGE (-1663 2687);
FORCEPROP 1 LAST MATERIAL CHIP
J 0
(-1550 2575);
DISPLAY 0.617021 (-1550 2575);
PAINT SKYBLUE (-1550 2575);
FORCEPROP 1 LAST TOLERANCE 1%
J 0
(-1575 2625);
DISPLAY 0.617021 (-1575 2625);
PAINT SKYBLUE (-1575 2625);
FORCEPROP 1 LAST PART_NUMBER G21796-066
J 0
(-1650 2550);
DISPLAY 0.617021 (-1650 2550);
PAINT BLUE (-1650 2550);
FORCEPROP 1 LAST LOCATION R3N9
J 0
(-1625 2725);
DISPLAY 0.617021 (-1625 2725);
PAINT AQUA (-1625 2725);
FORCEPROP 1 LAST PACK_TYPE 0402
J 0
(-1450 2625);
DISPLAY 0.617021 (-1450 2625);
PAINT SKYBLUE (-1450 2625);
FORCEPROP 1 LASTPIN (-1475 2675) $PN 2
J 0
(-1513 2687);
DISPLAY 0.617021 (-1513 2687);
PAINT ORANGE (-1513 2687);
FORCEPROP 2 LAST CDS_LOCATION R3N9
J 0
(-1625 2725);
DISPLAY 0.617021 (-1625 2725);
PAINT AQUA (-1625 2725);
DISPLAY INVISIBLE (-1625 2725);
FORCEPROP 2 LAST CDS_LIB mstr_discrete
J 0
(-1575 2675);
PAINT ORANGE (-1575 2675);
DISPLAY INVISIBLE (-1575 2675);
FORCEPROP 1 LAST PATH I66
J 0
(-1625 2825);
DISPLAY 0.978723 (-1625 2825);
PAINT WHITE (-1625 2825);
DISPLAY INVISIBLE (-1625 2825);
FORCEPROP 0 LAST ROOM SB
J 0
(-1625 2875);
DISPLAY 1.021277 (-1625 2875);
PAINT ORANGE (-1625 2875);
DISPLAY INVISIBLE (-1625 2875);
FORCEPROP 2 LAST SEC 1
J 0
(-1625 2875);
DISPLAY 0.680851 (-1625 2875);
PAINT MONO (-1625 2875);
DISPLAY INVISIBLE (-1625 2875);
FORCEPROP 0 LAST BOM_COST SB
J 0
(-1625 2975);
DISPLAY 1.021277 (-1625 2975);
PAINT ORANGE (-1625 2975);
DISPLAY INVISIBLE (-1625 2975);
FORCEPROP 2 LAST SEC_TYPE 0402
J 0
(-1625 2875);
DISPLAY 1.021277 (-1625 2875);
PAINT ORANGE (-1625 2875);
DISPLAY INVISIBLE (-1625 2875);
FORCEADD RES..2
(-1075 2475);
FORCEPROP 1 LASTPIN (-1075 2375) $PN 2
J 0
(-1070 2385);
DISPLAY 0.617021 (-1070 2385);
PAINT ORANGE (-1070 2385);
FORCEPROP 1 LASTPIN (-1075 2575) $PN 1
J 0
(-1070 2537);
DISPLAY 0.617021 (-1070 2537);
PAINT ORANGE (-1070 2537);
FORCEPROP 1 LAST WATTAGE 1/16W
J 0
(-1035 2450);
DISPLAY 0.617021 (-1035 2450);
PAINT SKYBLUE (-1035 2450);
FORCEPROP 1 LAST PACK_TYPE 0402
J 0
(-1035 2300);
DISPLAY 0.617021 (-1035 2300);
PAINT SKYBLUE (-1035 2300);
FORCEPROP 1 LAST TOLERANCE 1%
J 0
(-1030 2500);
DISPLAY 0.617021 (-1030 2500);
PAINT SKYBLUE (-1030 2500);
FORCEPROP 1 LAST VALUE 49.9
J 0
(-1030 2550);
DISPLAY 0.617021 (-1030 2550);
PAINT SKYBLUE (-1030 2550);
FORCEPROP 1 LAST PART_NUMBER G21796-047
J 0
(-1035 2350);
DISPLAY 0.617021 (-1035 2350);
PAINT BLUE (-1035 2350);
FORCEPROP 1 LAST LOCATION R3N14
J 0
(-1030 2600);
DISPLAY 0.617021 (-1030 2600);
PAINT AQUA (-1030 2600);
FORCEPROP 1 LAST MATERIAL EMPTY
J 0
(-1035 2400);
DISPLAY 0.617021 (-1035 2400);
PAINT RED (-1035 2400);
FORCEPROP 2 LAST CDS_LIB mstr_discrete
J 0
(-1075 2475);
PAINT ORANGE (-1075 2475);
DISPLAY INVISIBLE (-1075 2475);
FORCEPROP 2 LAST CDS_LOCATION R3N14
J 0
(-1030 2600);
DISPLAY 0.617021 (-1030 2600);
PAINT AQUA (-1030 2600);
DISPLAY INVISIBLE (-1030 2600);
FORCEPROP 0 LAST ROOM SB
J 0
(-1025 2650);
DISPLAY 1.021277 (-1025 2650);
PAINT ORANGE (-1025 2650);
DISPLAY INVISIBLE (-1025 2650);
FORCEPROP 1 LAST PATH I67
J 0
(-1025 2650);
DISPLAY 0.978723 (-1025 2650);
PAINT WHITE (-1025 2650);
DISPLAY INVISIBLE (-1025 2650);
FORCEPROP 2 LAST SEC_TYPE 0402
J 0
(-1025 2700);
DISPLAY 1.021277 (-1025 2700);
PAINT ORANGE (-1025 2700);
DISPLAY INVISIBLE (-1025 2700);
FORCEPROP 0 LAST BOM_COST SB
J 0
(-1025 2700);
DISPLAY 1.021277 (-1025 2700);
PAINT ORANGE (-1025 2700);
DISPLAY INVISIBLE (-1025 2700);
FORCEPROP 2 LAST SEC 1
J 0
(-1025 2700);
DISPLAY 0.680851 (-1025 2700);
PAINT MONO (-1025 2700);
DISPLAY INVISIBLE (-1025 2700);
FORCEADD OFFPAGE..2
(-600 2675);
FORCEPROP 2 LAST $XR0 21 
J 0
(-411 2675);
DISPLAY 0.638298 (-411 2675);
PAINT MONO (-411 2675);
FORCEPROP 2 LAST $XR1 55 
J 0
(-321 2675);
DISPLAY 0.638298 (-321 2675);
PAINT MONO (-321 2675);
FORCEPROP 1 LAST COMMENT_BODY TRUE
J 0
(-645 2580);
DISPLAY 0.872340 (-645 2580);
PAINT GREEN (-645 2580);
DISPLAY INVISIBLE (-645 2580);
FORCEPROP 2 LAST CDS_LIB mstr_standard
J 0
(-600 2675);
PAINT ORANGE (-600 2675);
DISPLAY INVISIBLE (-600 2675);
FORCEPROP 2 LAST PATH I68
J 0
(-425 2750);
DISPLAY 1.021277 (-425 2750);
PAINT ORANGE (-425 2750);
DISPLAY INVISIBLE (-425 2750);
FORCEPROP 1 LAST OFFPAGE TRUE
J 0
(-275 2550);
DISPLAY 0.872340 (-275 2550);
PAINT GREEN (-275 2550);
DISPLAY INVISIBLE (-275 2550);
FORCEADD GND..1
(-1075 2225);
FORCEPROP 3 LASTPIN (-1075 2275) SIG_NAME GND\g
J 0
(-1065 2285);
DISPLAY 0.659574 (-1065 2285);
PAINT MONO (-1065 2285);
DISPLAY INVISIBLE (-1065 2285);
FORCEPROP 1 LAST BODY_TYPE PLUMBING
J 0
(-1120 2182);
DISPLAY 0.340426 (-1120 2182);
PAINT GREEN (-1120 2182);
DISPLAY INVISIBLE (-1120 2182);
FORCEPROP 2 LAST CDS_LIB mstr_symbols
J 0
(-1075 2225);
PAINT ORANGE (-1075 2225);
DISPLAY INVISIBLE (-1075 2225);
FORCEPROP 1 LAST VOLTAGE 0.0V
J 0
(-1120 2182);
DISPLAY 0.340426 (-1120 2182);
PAINT SKYBLUE (-1120 2182);
DISPLAY INVISIBLE (-1120 2182);
FORCEPROP 1 LAST HDL_POWER GND
J 0
(-1075 2375);
DISPLAY 0.872340 (-1075 2375);
PAINT GREEN (-1075 2375);
DISPLAY INVISIBLE (-1075 2375);
FORCEPROP 1 LAST PATH I69
J 0
(-1000 2225);
DISPLAY 0.872340 (-1000 2225);
PAINT AQUA (-1000 2225);
DISPLAY INVISIBLE (-1000 2225);
FORCEPROP 1 LAST SIZE 1B
J 0
(-1000 2175);
DISPLAY 0.872340 (-1000 2175);
PAINT AQUA (-1000 2175);
DISPLAY INVISIBLE (-1000 2175);
FORCEADD RES..2
(-2300 4650);
FORCEPROP 1 LASTPIN (-2300 4550) $PN 2
J 0
(-2295 4560);
DISPLAY 0.617021 (-2295 4560);
PAINT ORANGE (-2295 4560);
FORCEPROP 1 LAST MATERIAL CHIP
J 0
(-2260 4575);
DISPLAY 0.617021 (-2260 4575);
PAINT SKYBLUE (-2260 4575);
FORCEPROP 1 LAST PACK_TYPE 0402
J 0
(-2260 4475);
DISPLAY 0.617021 (-2260 4475);
PAINT SKYBLUE (-2260 4475);
FORCEPROP 1 LAST TOLERANCE 1%
J 0
(-2255 4675);
DISPLAY 0.617021 (-2255 4675);
PAINT SKYBLUE (-2255 4675);
FORCEPROP 1 LASTPIN (-2300 4750) $PN 1
J 0
(-2295 4712);
DISPLAY 0.617021 (-2295 4712);
PAINT ORANGE (-2295 4712);
FORCEPROP 1 LAST LOCATION R3N13
J 0
(-2255 4775);
DISPLAY 0.617021 (-2255 4775);
PAINT AQUA (-2255 4775);
FORCEPROP 1 LAST VALUE 4.75K
J 0
(-2255 4725);
DISPLAY 0.617021 (-2255 4725);
PAINT SKYBLUE (-2255 4725);
FORCEPROP 1 LAST WATTAGE 1/16W
J 0
(-2260 4625);
DISPLAY 0.617021 (-2260 4625);
PAINT SKYBLUE (-2260 4625);
FORCEPROP 1 LAST PART_NUMBER G21796-072
J 0
(-2260 4525);
DISPLAY 0.617021 (-2260 4525);
PAINT BLUE (-2260 4525);
FORCEPROP 2 LAST CDS_LOCATION R3N13
J 0
(-2255 4775);
DISPLAY 0.617021 (-2255 4775);
PAINT AQUA (-2255 4775);
DISPLAY INVISIBLE (-2255 4775);
FORCEPROP 2 LAST CDS_LIB mstr_discrete
J 0
(-2300 4650);
PAINT ORANGE (-2300 4650);
DISPLAY INVISIBLE (-2300 4650);
FORCEPROP 1 LAST PATH I71
J 0
(-2250 4825);
DISPLAY 0.978723 (-2250 4825);
PAINT WHITE (-2250 4825);
DISPLAY INVISIBLE (-2250 4825);
FORCEPROP 0 LAST ROOM SB
J 0
(-2250 4825);
DISPLAY 1.021277 (-2250 4825);
PAINT ORANGE (-2250 4825);
DISPLAY INVISIBLE (-2250 4825);
FORCEPROP 2 LAST SEC 1
J 0
(-2250 4875);
DISPLAY 0.680851 (-2250 4875);
PAINT MONO (-2250 4875);
DISPLAY INVISIBLE (-2250 4875);
FORCEPROP 0 LAST BOM_COST SB
J 0
(-2250 4875);
DISPLAY 1.021277 (-2250 4875);
PAINT ORANGE (-2250 4875);
DISPLAY INVISIBLE (-2250 4875);
FORCEPROP 2 LAST SEC_TYPE 0402
J 0
(-2250 4875);
DISPLAY 1.021277 (-2250 4875);
PAINT ORANGE (-2250 4875);
DISPLAY INVISIBLE (-2250 4875);
FORCEADD P3V3_STBY..1
(-2300 4875);
FORCEPROP 3 LASTPIN (-2300 4825) SIG_NAME P3V3_STBY\g
J 0
(-2290 4835);
DISPLAY 0.659574 (-2290 4835);
PAINT MONO (-2290 4835);
DISPLAY INVISIBLE (-2290 4835);
FORCEPROP 1 LAST HDL_POWER P3V3_STBY
J 0
(-2600 4750);
DISPLAY 0.872340 (-2600 4750);
PAINT ORANGE (-2600 4750);
DISPLAY INVISIBLE (-2600 4750);
FORCEPROP 1 LAST BODY_TYPE PLUMBING
J 0
(-2345 4832);
DISPLAY 0.340426 (-2345 4832);
PAINT GREEN (-2345 4832);
DISPLAY INVISIBLE (-2345 4832);
FORCEPROP 1 LAST VOLTAGE 3.3V
J 0
(-2345 4832);
DISPLAY 0.340426 (-2345 4832);
PAINT SKYBLUE (-2345 4832);
DISPLAY INVISIBLE (-2345 4832);
FORCEPROP 1 LAST SIZE 1B
J 0
(-2255 4897);
DISPLAY 0.340426 (-2255 4897);
PAINT GREEN (-2255 4897);
DISPLAY INVISIBLE (-2255 4897);
FORCEPROP 2 LAST CDS_LIB mstr_symbols
J 0
(-2300 4875);
PAINT ORANGE (-2300 4875);
DISPLAY INVISIBLE (-2300 4875);
FORCEPROP 1 LAST PATH I72
J 0
(-2255 4877);
DISPLAY 0.340426 (-2255 4877);
PAINT GREEN (-2255 4877);
DISPLAY INVISIBLE (-2255 4877);
FORCEADD LBG_CORE_QAT_EXT_D..5
(-4025 3025);
FORCEPROP 2 LASTPIN (-4925 1725) $PN BN29
J 2
(-4935 1735);
DISPLAY 0.617021 (-4935 1735);
PAINT ORANGE (-4935 1735);
FORCEPROP 2 LASTPIN (-4925 1625) $PN BV16
J 2
(-4935 1635);
DISPLAY 0.617021 (-4935 1635);
PAINT ORANGE (-4935 1635);
FORCEPROP 2 LASTPIN (-4925 1775) $PN BL29
J 2
(-4935 1785);
DISPLAY 0.617021 (-4935 1785);
PAINT ORANGE (-4935 1785);
FORCEPROP 2 LASTPIN (-4925 1925) $PN BL26
J 2
(-4935 1935);
DISPLAY 0.617021 (-4935 1935);
PAINT ORANGE (-4935 1935);
FORCEPROP 2 LASTPIN (-4925 1975) $PN BN26
J 2
(-4935 1985);
DISPLAY 0.617021 (-4935 1985);
PAINT ORANGE (-4935 1985);
FORCEPROP 2 LASTPIN (-4925 1875) $PN BB29
J 2
(-4935 1885);
DISPLAY 0.617021 (-4935 1885);
PAINT ORANGE (-4935 1885);
FORCEPROP 1 LAST PART_NUMBER H91415-002
J 0
(-4875 1425);
DISPLAY 0.617021 (-4875 1425);
PAINT BLUE (-4875 1425);
FORCEPROP 2 LASTPIN (-4925 2225) $PN BJ29
J 2
(-4935 2235);
DISPLAY 0.617021 (-4935 2235);
PAINT ORANGE (-4935 2235);
FORCEPROP 2 LASTPIN (-4925 2175) $PN BG29
J 2
(-4935 2185);
DISPLAY 0.617021 (-4935 2185);
PAINT ORANGE (-4935 2185);
FORCEPROP 2 LASTPIN (-4925 2125) $PN BF31
J 2
(-4935 2135);
DISPLAY 0.617021 (-4935 2135);
PAINT ORANGE (-4935 2135);
FORCEPROP 2 LASTPIN (-4925 2075) $PN BH31
J 2
(-4935 2085);
DISPLAY 0.617021 (-4935 2085);
PAINT ORANGE (-4935 2085);
FORCEPROP 2 LASTPIN (-4925 2475) $PN BH35
J 2
(-4935 2485);
DISPLAY 0.617021 (-4935 2485);
PAINT ORANGE (-4935 2485);
FORCEPROP 2 LASTPIN (-4925 2425) $PN BF35
J 2
(-4935 2435);
DISPLAY 0.617021 (-4935 2435);
PAINT ORANGE (-4935 2435);
FORCEPROP 2 LASTPIN (-4925 2375) $PN BG37
J 2
(-4935 2385);
DISPLAY 0.617021 (-4935 2385);
PAINT ORANGE (-4935 2385);
FORCEPROP 2 LASTPIN (-4925 2325) $PN BJ37
J 2
(-4935 2335);
DISPLAY 0.617021 (-4935 2335);
PAINT ORANGE (-4935 2335);
FORCEPROP 2 LASTPIN (-4925 2725) $PN AR54
J 2
(-4935 2735);
DISPLAY 0.617021 (-4935 2735);
PAINT ORANGE (-4935 2735);
FORCEPROP 2 LASTPIN (-4925 2675) $PN AT56
J 2
(-4935 2685);
DISPLAY 0.617021 (-4935 2685);
PAINT ORANGE (-4935 2685);
FORCEPROP 2 LASTPIN (-4925 2975) $PN AF54
J 2
(-4935 2985);
DISPLAY 0.617021 (-4935 2985);
PAINT ORANGE (-4935 2985);
FORCEPROP 2 LASTPIN (-4925 3025) $PN AH54
J 2
(-4935 3035);
DISPLAY 0.617021 (-4935 3035);
PAINT ORANGE (-4935 3035);
FORCEPROP 2 LASTPIN (-4925 2825) $PN AD54
J 2
(-4935 2835);
DISPLAY 0.617021 (-4935 2835);
PAINT ORANGE (-4935 2835);
FORCEPROP 2 LASTPIN (-4925 2875) $PN U54
J 2
(-4935 2885);
DISPLAY 0.617021 (-4935 2885);
PAINT ORANGE (-4935 2885);
FORCEPROP 2 LASTPIN (-4925 3175) $PN AL56
J 2
(-4935 3185);
DISPLAY 0.617021 (-4935 3185);
PAINT ORANGE (-4935 3185);
FORCEPROP 2 LASTPIN (-4925 3125) $PN AN54
J 2
(-4935 3135);
DISPLAY 0.617021 (-4935 3135);
PAINT ORANGE (-4935 3135);
FORCEPROP 2 LASTPIN (-4925 3075) $PN AP56
J 2
(-4935 3085);
DISPLAY 0.617021 (-4935 3085);
PAINT ORANGE (-4935 3085);
FORCEPROP 2 LASTPIN (-4925 3275) $PN R13
J 2
(-4935 3285);
DISPLAY 0.617021 (-4935 3285);
PAINT ORANGE (-4935 3285);
FORCEPROP 2 LASTPIN (-4925 3325) $PN M7
J 2
(-4935 3335);
DISPLAY 0.617021 (-4935 3335);
PAINT ORANGE (-4935 3335);
FORCEPROP 2 LASTPIN (-4925 3525) $PN Y56
J 2
(-4935 3535);
DISPLAY 0.617021 (-4935 3535);
PAINT ORANGE (-4935 3535);
FORCEPROP 2 LASTPIN (-4925 3475) $PN W54
J 2
(-4935 3485);
DISPLAY 0.617021 (-4935 3485);
PAINT ORANGE (-4935 3485);
FORCEPROP 2 LASTPIN (-4925 3425) $PN AK54
J 2
(-4935 3435);
DISPLAY 0.617021 (-4935 3435);
PAINT ORANGE (-4935 3435);
FORCEPROP 2 LASTPIN (-4925 3625) $PN AA54
J 2
(-4935 3635);
DISPLAY 0.617021 (-4935 3635);
PAINT ORANGE (-4935 3635);
FORCEPROP 2 LASTPIN (-4925 3575) $PN V56
J 2
(-4935 3585);
DISPLAY 0.617021 (-4935 3585);
PAINT ORANGE (-4935 3585);
FORCEPROP 2 LASTPIN (-4925 3775) $PN P22
J 2
(-4935 3785);
DISPLAY 0.617021 (-4935 3785);
PAINT ORANGE (-4935 3785);
FORCEPROP 2 LASTPIN (-4925 4025) $PN C15
J 2
(-4935 4035);
DISPLAY 0.617021 (-4935 4035);
PAINT ORANGE (-4935 4035);
FORCEPROP 2 LASTPIN (-4925 3975) $PN M11
J 2
(-4935 3985);
DISPLAY 0.617021 (-4935 3985);
PAINT ORANGE (-4935 3985);
FORCEPROP 2 LASTPIN (-4925 3925) $PN H13
J 2
(-4935 3935);
DISPLAY 0.617021 (-4935 3935);
PAINT ORANGE (-4935 3935);
FORCEPROP 2 LASTPIN (-4925 3875) $PN G15
J 2
(-4935 3885);
DISPLAY 0.617021 (-4935 3885);
PAINT ORANGE (-4935 3885);
FORCEPROP 2 LASTPIN (-4925 4075) $PN D14
J 2
(-4935 4085);
DISPLAY 0.617021 (-4935 4085);
PAINT ORANGE (-4935 4085);
FORCEPROP 2 LASTPIN (-4925 4175) $PN G11
J 2
(-4935 4185);
DISPLAY 0.617021 (-4935 4185);
PAINT ORANGE (-4935 4185);
FORCEPROP 2 LASTPIN (-4925 4275) $PN C13
J 2
(-4935 4285);
DISPLAY 0.617021 (-4935 4285);
PAINT ORANGE (-4935 4285);
FORCEPROP 2 LASTPIN (-4925 4225) $PN H9
J 2
(-4935 4235);
DISPLAY 0.617021 (-4935 4235);
PAINT ORANGE (-4935 4235);
FORCEPROP 2 LASTPIN (-4925 4125) $PN B16
J 2
(-4935 4135);
DISPLAY 0.617021 (-4935 4135);
PAINT ORANGE (-4935 4135);
FORCEPROP 2 LASTPIN (-4925 4325) $PN A15
J 2
(-4935 4335);
DISPLAY 0.617021 (-4935 4335);
PAINT ORANGE (-4935 4335);
FORCEPROP 2 LASTPIN (-4925 4425) $PN A13
J 2
(-4935 4435);
DISPLAY 0.617021 (-4935 4435);
PAINT ORANGE (-4935 4435);
FORCEPROP 2 LASTPIN (-4925 4375) $PN B14
J 2
(-4935 4385);
DISPLAY 0.617021 (-4935 4385);
PAINT ORANGE (-4935 4385);
FORCEPROP 1 LAST MATERIAL IC
J 0
(-4875 4625);
DISPLAY 0.617021 (-4875 4625);
PAINT SKYBLUE (-4875 4625);
FORCEPROP 1 LAST LOCATION U7C1
J 0
(-4900 4700);
DISPLAY 0.617021 (-4900 4700);
PAINT AQUA (-4900 4700);
FORCEPROP 2 LASTPIN (-3125 1725) $PN BJ40
J 0
(-3115 1735);
DISPLAY 0.617021 (-3115 1735);
PAINT ORANGE (-3115 1735);
FORCEPROP 2 LASTPIN (-3125 1775) $PN BG40
J 0
(-3115 1785);
DISPLAY 0.617021 (-3115 1785);
PAINT ORANGE (-3115 1785);
FORCEPROP 2 LASTPIN (-3125 1925) $PN BL33
J 0
(-3115 1935);
DISPLAY 0.617021 (-3115 1935);
PAINT ORANGE (-3115 1935);
FORCEPROP 2 LASTPIN (-3125 1975) $PN BN33
J 0
(-3115 1985);
DISPLAY 0.617021 (-3115 1985);
PAINT ORANGE (-3115 1985);
FORCEPROP 2 LASTPIN (-3125 1625) $PN BY16
J 0
(-3115 1635);
DISPLAY 0.617021 (-3115 1635);
PAINT ORANGE (-3115 1635);
FORCEPROP 2 LASTPIN (-3125 1875) $PN BD42
J 0
(-3115 1885);
DISPLAY 0.617021 (-3115 1885);
PAINT ORANGE (-3115 1885);
FORCEPROP 2 LASTPIN (-3125 2825) $PN V15
J 0
(-3115 2835);
DISPLAY 0.617021 (-3115 2835);
PAINT ORANGE (-3115 2835);
FORCEPROP 2 LASTPIN (-3125 3875) $PN BV19
J 0
(-3115 3885);
DISPLAY 0.617021 (-3115 3885);
PAINT ORANGE (-3115 3885);
FORCEPROP 2 LASTPIN (-3125 2975) $PN P26
J 0
(-3115 2985);
DISPLAY 0.617021 (-3115 2985);
PAINT ORANGE (-3115 2985);
FORCEPROP 2 LASTPIN (-3125 2925) $PN R24
J 0
(-3115 2935);
DISPLAY 0.617021 (-3115 2935);
PAINT ORANGE (-3115 2935);
FORCEPROP 2 LASTPIN (-3125 4025) $PN P15
J 0
(-3115 4035);
DISPLAY 0.617021 (-3115 4035);
PAINT ORANGE (-3115 4035);
FORCEPROP 2 LASTPIN (-3125 2625) $PN V7
J 0
(-3115 2635);
DISPLAY 0.617021 (-3115 2635);
PAINT ORANGE (-3115 2635);
FORCEPROP 2 LASTPIN (-3125 2675) $PN U13
J 0
(-3115 2685);
DISPLAY 0.617021 (-3115 2685);
PAINT ORANGE (-3115 2685);
FORCEPROP 2 LASTPIN (-3125 3925) $PN U17
J 0
(-3115 3935);
DISPLAY 0.617021 (-3115 3935);
PAINT ORANGE (-3115 3935);
FORCEPROP 2 LASTPIN (-3125 2775) $PN U9
J 0
(-3115 2785);
DISPLAY 0.617021 (-3115 2785);
PAINT ORANGE (-3115 2785);
FORCEPROP 2 LASTPIN (-3125 2475) $PN BM31
J 0
(-3115 2485);
DISPLAY 0.617021 (-3115 2485);
PAINT ORANGE (-3115 2485);
FORCEPROP 2 LASTPIN (-3125 2425) $PN BR31
J 0
(-3115 2435);
DISPLAY 0.617021 (-3115 2435);
PAINT ORANGE (-3115 2435);
FORCEPROP 2 LASTPIN (-3125 2375) $PN BR35
J 0
(-3115 2385);
DISPLAY 0.617021 (-3115 2385);
PAINT ORANGE (-3115 2385);
FORCEPROP 2 LASTPIN (-3125 2325) $PN BM35
J 0
(-3115 2335);
DISPLAY 0.617021 (-3115 2335);
PAINT ORANGE (-3115 2335);
FORCEPROP 2 LASTPIN (-3125 2225) $PN BR24
J 0
(-3115 2235);
DISPLAY 0.617021 (-3115 2235);
PAINT ORANGE (-3115 2235);
FORCEPROP 2 LASTPIN (-3125 2175) $PN BM24
J 0
(-3115 2185);
DISPLAY 0.617021 (-3115 2185);
PAINT ORANGE (-3115 2185);
FORCEPROP 2 LASTPIN (-3125 2125) $PN BR27
J 0
(-3115 2135);
DISPLAY 0.617021 (-3115 2135);
PAINT ORANGE (-3115 2135);
FORCEPROP 2 LASTPIN (-3125 2075) $PN BM27
J 0
(-3115 2085);
DISPLAY 0.617021 (-3115 2085);
PAINT ORANGE (-3115 2085);
FORCEPROP 2 LASTPIN (-3125 4075) $PN M15
J 0
(-3115 4085);
DISPLAY 0.617021 (-3115 4085);
PAINT ORANGE (-3115 4085);
FORCEPROP 2 LASTPIN (-3125 4175) $PN K9
J 0
(-3115 4185);
DISPLAY 0.617021 (-3115 4185);
PAINT ORANGE (-3115 4185);
FORCEPROP 2 LASTPIN (-3125 4275) $PN BY19
J 0
(-3115 4285);
DISPLAY 0.617021 (-3115 4285);
PAINT ORANGE (-3115 4285);
FORCEPROP 2 LASTPIN (-3125 4125) $PN P7
J 0
(-3115 4135);
DISPLAY 0.617021 (-3115 4135);
PAINT ORANGE (-3115 4135);
FORCEPROP 2 LASTPIN (-3125 4425) $PN R9
J 0
(-3115 4435);
DISPLAY 0.617021 (-3115 4435);
PAINT ORANGE (-3115 4435);
FORCEPROP 2 LASTPIN (-3125 4325) $PN R17
J 0
(-3115 4335);
DISPLAY 0.617021 (-3115 4335);
PAINT ORANGE (-3115 4335);
FORCEPROP 2 LASTPIN (-3125 4375) $PN K13
J 0
(-3115 4385);
DISPLAY 0.617021 (-3115 4385);
PAINT ORANGE (-3115 4385);
FORCEPROP 2 LAST CDS_LOCATION U7C1
J 0
(-4900 4700);
DISPLAY 0.617021 (-4900 4700);
PAINT AQUA (-4900 4700);
DISPLAY INVISIBLE (-4900 4700);
FORCEPROP 2 LAST SEC 5
J 0
(-4900 4750);
DISPLAY 0.680851 (-4900 4750);
PAINT MONO (-4900 4750);
DISPLAY INVISIBLE (-4900 4750);
FORCEPROP 2 LAST SEC_TYPE BGA1
J 0
(-4900 4750);
DISPLAY 1.021277 (-4900 4750);
PAINT ORANGE (-4900 4750);
DISPLAY INVISIBLE (-4900 4750);
FORCEPROP 1 LAST PACK_TYPE BGA1
J 0
(-4875 4725);
PAINT SKYBLUE (-4875 4725);
DISPLAY INVISIBLE (-4875 4725);
FORCEPROP 0 LAST ROOM SB
J 0
(-4475 4925);
DISPLAY 1.361702 (-4475 4925);
PAINT ORANGE (-4475 4925);
DISPLAY INVISIBLE (-4475 4925);
FORCEPROP 0 LAST BOM_COST SB
J 0
(-4475 5025);
DISPLAY 1.361702 (-4475 5025);
PAINT ORANGE (-4475 5025);
DISPLAY INVISIBLE (-4475 5025);
FORCEPROP 2 LAST CDS_LIB mstr_u_proc
J 0
(-4025 3025);
PAINT ORANGE (-4025 3025);
DISPLAY INVISIBLE (-4025 3025);
FORCEPROP 1 LAST PATH I73
J 0
(-4025 4625);
PAINT GREEN (-4025 4625);
DISPLAY INVISIBLE (-4025 4625);
FORCEADD CRYSTAL..1
(-7400 850);
FORCEPROP 1 LASTPIN (-7500 850) $PN 1
J 2
(-7455 860);
DISPLAY 0.617021 (-7455 860);
PAINT AQUA (-7455 860);
FORCEPROP 1 LAST VALUE 25.000MHZ
J 1
(-7393 911);
DISPLAY 0.617021 (-7393 911);
PAINT SKYBLUE (-7393 911);
FORCEPROP 1 LAST LOCATION Y8C1
J 1
(-7395 949);
DISPLAY 0.617021 (-7395 949);
PAINT AQUA (-7395 949);
FORCEPROP 1 LAST MATERIAL IC
J 0
(-7411 766);
DISPLAY 0.617021 (-7411 766);
PAINT SKYBLUE (-7411 766);
FORCEPROP 1 LASTPIN (-7300 850) $PN 3
J 0
(-7335 860);
DISPLAY 0.617021 (-7335 860);
PAINT AQUA (-7335 860);
FORCEPROP 1 LAST PART_NUMBER H19611-001
J 0
(-7575 1000);
DISPLAY 0.617021 (-7575 1000);
PAINT BLUE (-7575 1000);
FORCEPROP 1 LAST PACK_TYPE 2013
J 0
(-7412 758);
DISPLAY 0.702128 (-7412 758);
PAINT SKYBLUE (-7412 758);
DISPLAY INVISIBLE (-7412 758);
FORCEPROP 2 LAST CDS_LOCATION Y8C1
J 1
(-7395 949);
DISPLAY 0.617021 (-7395 949);
PAINT AQUA (-7395 949);
DISPLAY INVISIBLE (-7395 949);
FORCEPROP 2 LAST CDS_LIB mstr_discrete
J 0
(-7400 850);
PAINT ORANGE (-7400 850);
DISPLAY INVISIBLE (-7400 850);
FORCEPROP 1 LAST PATH I76
J 0
(-7375 950);
DISPLAY 0.872340 (-7375 950);
PAINT PINK (-7375 950);
DISPLAY INVISIBLE (-7375 950);
FORCEPROP 0 LAST ROOM SB
J 0
(-7575 1075);
DISPLAY 1.021277 (-7575 1075);
PAINT ORANGE (-7575 1075);
DISPLAY INVISIBLE (-7575 1075);
FORCEPROP 2 LAST SEC_TYPE 2013
J 0
(-7575 1050);
DISPLAY 1.021277 (-7575 1050);
PAINT ORANGE (-7575 1050);
DISPLAY INVISIBLE (-7575 1050);
FORCEPROP 2 LAST SEC 1
J 0
(-7575 1050);
DISPLAY 0.680851 (-7575 1050);
PAINT MONO (-7575 1050);
DISPLAY INVISIBLE (-7575 1050);
FORCEPROP 0 LAST BOM_COST SB
J 0
(-7575 1125);
DISPLAY 1.021277 (-7575 1125);
PAINT ORANGE (-7575 1125);
DISPLAY INVISIBLE (-7575 1125);
FORCEADD CAP..1
(-7250 600);
FORCEPROP 1 LASTPIN (-7250 500) $PN 2
J 0
(-7240 480);
DISPLAY 0.617021 (-7240 480);
PAINT ORANGE (-7240 480);
FORCEPROP 1 LASTPIN (-7250 700) $PN 1
J 0
(-7240 680);
DISPLAY 0.617021 (-7240 680);
PAINT ORANGE (-7240 680);
FORCEPROP 1 LAST MATERIAL COG
J 0
(-7200 500);
DISPLAY 0.617021 (-7200 500);
PAINT SKYBLUE (-7200 500);
FORCEPROP 1 LAST VOLTAGE 50V
J 0
(-7200 600);
DISPLAY 0.617021 (-7200 600);
PAINT SKYBLUE (-7200 600);
FORCEPROP 1 LAST PACK_TYPE 0402LF
J 0
(-7200 400);
DISPLAY 0.617021 (-7200 400);
PAINT SKYBLUE (-7200 400);
FORCEPROP 1 LAST TOLERANCE 5%
J 0
(-7200 550);
DISPLAY 0.617021 (-7200 550);
PAINT SKYBLUE (-7200 550);
FORCEPROP 1 LAST VALUE 33.0PF
J 0
(-7200 650);
DISPLAY 0.617021 (-7200 650);
PAINT SKYBLUE (-7200 650);
FORCEPROP 1 LAST PART_NUMBER A36095-031
J 0
(-7200 450);
DISPLAY 0.617021 (-7200 450);
PAINT BLUE (-7200 450);
FORCEPROP 1 LAST LOCATION C8C2
J 0
(-7200 700);
DISPLAY 0.617021 (-7200 700);
PAINT AQUA (-7200 700);
FORCEPROP 2 LAST CDS_LOCATION C8C2
J 0
(-7200 700);
DISPLAY 0.617021 (-7200 700);
PAINT AQUA (-7200 700);
DISPLAY INVISIBLE (-7200 700);
FORCEPROP 2 LAST CDS_LIB mstr_discrete
J 0
(-7250 600);
PAINT ORANGE (-7250 600);
DISPLAY INVISIBLE (-7250 600);
FORCEPROP 0 LAST ROOM SB
J 0
(-7200 750);
DISPLAY 1.021277 (-7200 750);
PAINT ORANGE (-7200 750);
DISPLAY INVISIBLE (-7200 750);
FORCEPROP 1 LAST PATH I77
J 0
(-7200 750);
DISPLAY 0.978723 (-7200 750);
PAINT WHITE (-7200 750);
DISPLAY INVISIBLE (-7200 750);
FORCEPROP 2 LAST SEC_TYPE 0402LF
J 0
(-7200 800);
DISPLAY 1.021277 (-7200 800);
PAINT ORANGE (-7200 800);
DISPLAY INVISIBLE (-7200 800);
FORCEPROP 2 LAST SEC 1
J 0
(-7200 800);
DISPLAY 0.680851 (-7200 800);
PAINT MONO (-7200 800);
DISPLAY INVISIBLE (-7200 800);
FORCEPROP 0 LAST BOM_COST SB
J 0
(-7200 800);
DISPLAY 1.021277 (-7200 800);
PAINT ORANGE (-7200 800);
DISPLAY INVISIBLE (-7200 800);
FORCEADD GND..1
(-7250 400);
FORCEPROP 3 LASTPIN (-7250 450) SIG_NAME GND\g
J 0
(-7240 460);
DISPLAY 0.659574 (-7240 460);
PAINT MONO (-7240 460);
DISPLAY INVISIBLE (-7240 460);
FORCEPROP 1 LAST VOLTAGE 0.0V
J 0
(-7295 357);
DISPLAY 0.340426 (-7295 357);
PAINT SKYBLUE (-7295 357);
DISPLAY INVISIBLE (-7295 357);
FORCEPROP 1 LAST BODY_TYPE PLUMBING
J 0
(-7295 357);
DISPLAY 0.340426 (-7295 357);
PAINT GREEN (-7295 357);
DISPLAY INVISIBLE (-7295 357);
FORCEPROP 1 LAST SIZE 1B
J 0
(-7175 350);
DISPLAY 0.872340 (-7175 350);
PAINT AQUA (-7175 350);
DISPLAY INVISIBLE (-7175 350);
FORCEPROP 1 LAST PATH I78
J 0
(-7175 400);
DISPLAY 0.872340 (-7175 400);
PAINT AQUA (-7175 400);
DISPLAY INVISIBLE (-7175 400);
FORCEPROP 2 LAST CDS_LIB mstr_symbols
J 0
(-7250 400);
PAINT ORANGE (-7250 400);
DISPLAY INVISIBLE (-7250 400);
FORCEPROP 1 LAST HDL_POWER GND
J 0
(-7250 550);
DISPLAY 0.872340 (-7250 550);
PAINT GREEN (-7250 550);
DISPLAY INVISIBLE (-7250 550);
FORCEADD CAP..1
(-7700 625);
FORCEPROP 1 LASTPIN (-7700 525) $PN 2
J 0
(-7690 505);
DISPLAY 0.617021 (-7690 505);
PAINT ORANGE (-7690 505);
FORCEPROP 1 LASTPIN (-7700 725) $PN 1
J 0
(-7690 705);
DISPLAY 0.617021 (-7690 705);
PAINT ORANGE (-7690 705);
FORCEPROP 1 LAST PACK_TYPE 0402LF
J 0
(-7650 425);
DISPLAY 0.617021 (-7650 425);
PAINT SKYBLUE (-7650 425);
FORCEPROP 1 LAST PART_NUMBER A36095-031
J 0
(-7650 475);
DISPLAY 0.617021 (-7650 475);
PAINT BLUE (-7650 475);
FORCEPROP 1 LAST LOCATION C8C1
J 0
(-7650 725);
DISPLAY 0.617021 (-7650 725);
PAINT AQUA (-7650 725);
FORCEPROP 1 LAST VALUE 33.0PF
J 0
(-7650 675);
DISPLAY 0.617021 (-7650 675);
PAINT SKYBLUE (-7650 675);
FORCEPROP 1 LAST TOLERANCE 5%
J 0
(-7650 575);
DISPLAY 0.617021 (-7650 575);
PAINT SKYBLUE (-7650 575);
FORCEPROP 1 LAST VOLTAGE 50V
J 0
(-7650 625);
DISPLAY 0.617021 (-7650 625);
PAINT SKYBLUE (-7650 625);
FORCEPROP 1 LAST MATERIAL COG
J 0
(-7650 525);
DISPLAY 0.617021 (-7650 525);
PAINT SKYBLUE (-7650 525);
FORCEPROP 2 LAST CDS_LIB mstr_discrete
J 0
(-7700 625);
PAINT ORANGE (-7700 625);
DISPLAY INVISIBLE (-7700 625);
FORCEPROP 2 LAST CDS_LOCATION C8C1
J 0
(-7650 725);
DISPLAY 0.617021 (-7650 725);
PAINT AQUA (-7650 725);
DISPLAY INVISIBLE (-7650 725);
FORCEPROP 2 LAST SEC 1
J 0
(-7650 825);
DISPLAY 0.680851 (-7650 825);
PAINT MONO (-7650 825);
DISPLAY INVISIBLE (-7650 825);
FORCEPROP 0 LAST BOM_COST SB
J 0
(-7650 825);
DISPLAY 1.021277 (-7650 825);
PAINT ORANGE (-7650 825);
DISPLAY INVISIBLE (-7650 825);
FORCEPROP 2 LAST SEC_TYPE 0402LF
J 0
(-7650 825);
DISPLAY 1.021277 (-7650 825);
PAINT ORANGE (-7650 825);
DISPLAY INVISIBLE (-7650 825);
FORCEPROP 1 LAST PATH I79
J 0
(-7650 775);
DISPLAY 0.978723 (-7650 775);
PAINT WHITE (-7650 775);
DISPLAY INVISIBLE (-7650 775);
FORCEPROP 0 LAST ROOM SB
J 0
(-7650 775);
DISPLAY 1.021277 (-7650 775);
PAINT ORANGE (-7650 775);
DISPLAY INVISIBLE (-7650 775);
FORCEADD GND..1
(-7700 425);
FORCEPROP 3 LASTPIN (-7700 475) SIG_NAME GND\g
J 0
(-7690 485);
DISPLAY 0.659574 (-7690 485);
PAINT MONO (-7690 485);
DISPLAY INVISIBLE (-7690 485);
FORCEPROP 1 LAST VOLTAGE 0.0V
J 0
(-7745 382);
DISPLAY 0.340426 (-7745 382);
PAINT SKYBLUE (-7745 382);
DISPLAY INVISIBLE (-7745 382);
FORCEPROP 2 LAST CDS_LIB mstr_symbols
J 0
(-7700 425);
PAINT ORANGE (-7700 425);
DISPLAY INVISIBLE (-7700 425);
FORCEPROP 1 LAST BODY_TYPE PLUMBING
J 0
(-7745 382);
DISPLAY 0.340426 (-7745 382);
PAINT GREEN (-7745 382);
DISPLAY INVISIBLE (-7745 382);
FORCEPROP 1 LAST HDL_POWER GND
J 0
(-7700 575);
DISPLAY 0.872340 (-7700 575);
PAINT GREEN (-7700 575);
DISPLAY INVISIBLE (-7700 575);
FORCEPROP 1 LAST SIZE 1B
J 0
(-7625 375);
DISPLAY 0.872340 (-7625 375);
PAINT AQUA (-7625 375);
DISPLAY INVISIBLE (-7625 375);
FORCEPROP 1 LAST PATH I80
J 0
(-7625 425);
DISPLAY 0.872340 (-7625 425);
PAINT AQUA (-7625 425);
DISPLAY INVISIBLE (-7625 425);
FORCEADD OFFPAGE..2
(-7125 1150);
FORCEPROP 2 LAST $XR0 118 
J 0
(-6936 1150);
DISPLAY 0.638298 (-6936 1150);
PAINT MONO (-6936 1150);
FORCEPROP 1 LAST COMMENT_BODY TRUE
J 0
(-7170 1055);
DISPLAY 0.872340 (-7170 1055);
PAINT GREEN (-7170 1055);
DISPLAY INVISIBLE (-7170 1055);
FORCEPROP 2 LAST CDS_LIB mstr_standard
J 0
(-7125 1150);
PAINT ORANGE (-7125 1150);
DISPLAY INVISIBLE (-7125 1150);
FORCEPROP 2 LAST PATH I86
J 0
(-6950 1225);
DISPLAY 1.021277 (-6950 1225);
PAINT ORANGE (-6950 1225);
DISPLAY INVISIBLE (-6950 1225);
FORCEPROP 1 LAST OFFPAGE TRUE
J 0
(-6800 1025);
DISPLAY 0.872340 (-6800 1025);
PAINT GREEN (-6800 1025);
DISPLAY INVISIBLE (-6800 1025);
FORCEADD OFFPAGE..2
(-6750 850);
FORCEPROP 2 LAST $XR0 118 
J 0
(-6561 850);
DISPLAY 0.638298 (-6561 850);
PAINT MONO (-6561 850);
FORCEPROP 1 LAST COMMENT_BODY TRUE
J 0
(-6795 755);
DISPLAY 0.872340 (-6795 755);
PAINT GREEN (-6795 755);
DISPLAY INVISIBLE (-6795 755);
FORCEPROP 2 LAST CDS_LIB mstr_standard
J 0
(-6750 850);
PAINT ORANGE (-6750 850);
DISPLAY INVISIBLE (-6750 850);
FORCEPROP 2 LAST PATH I87
J 0
(-6575 925);
DISPLAY 1.021277 (-6575 925);
PAINT ORANGE (-6575 925);
DISPLAY INVISIBLE (-6575 925);
FORCEPROP 1 LAST OFFPAGE TRUE
J 0
(-6425 725);
DISPLAY 0.872340 (-6425 725);
PAINT GREEN (-6425 725);
DISPLAY INVISIBLE (-6425 725);
FORCEADD OFFPAGE..1
(-5675 1625);
FORCEPROP 2 LAST $XR0 118 
J 0
(-5957 1625);
DISPLAY 0.638298 (-5957 1625);
PAINT MONO (-5957 1625);
FORCEPROP 2 LAST CDS_LIB mstr_standard
J 0
(-5675 1625);
PAINT ORANGE (-5675 1625);
DISPLAY INVISIBLE (-5675 1625);
FORCEPROP 1 LAST COMMENT_BODY TRUE
J 0
(-5550 1525);
DISPLAY 0.872340 (-5550 1525);
PAINT GREEN (-5550 1525);
DISPLAY INVISIBLE (-5550 1525);
FORCEPROP 1 LAST OFFPAGE TRUE
J 0
(-5350 1500);
DISPLAY 0.872340 (-5350 1500);
PAINT GREEN (-5350 1500);
DISPLAY INVISIBLE (-5350 1500);
FORCEPROP 2 LAST PATH I89
J 0
(-5625 1700);
DISPLAY 1.021277 (-5625 1700);
PAINT ORANGE (-5625 1700);
DISPLAY INVISIBLE (-5625 1700);
FORCEADD OFFPAGE..2
(-1950 1625);
FORCEPROP 2 LAST $XR0 118 
J 0
(-1761 1625);
DISPLAY 0.638298 (-1761 1625);
PAINT MONO (-1761 1625);
FORCEPROP 1 LAST COMMENT_BODY TRUE
J 0
(-1995 1530);
DISPLAY 0.872340 (-1995 1530);
PAINT GREEN (-1995 1530);
DISPLAY INVISIBLE (-1995 1530);
FORCEPROP 1 LAST OFFPAGE TRUE
J 0
(-1625 1500);
DISPLAY 0.872340 (-1625 1500);
PAINT GREEN (-1625 1500);
DISPLAY INVISIBLE (-1625 1500);
FORCEPROP 2 LAST CDS_LIB mstr_standard
J 0
(-1950 1625);
PAINT ORANGE (-1950 1625);
DISPLAY INVISIBLE (-1950 1625);
FORCEPROP 2 LAST PATH I91
J 0
(-1775 1700);
DISPLAY 1.021277 (-1775 1700);
PAINT ORANGE (-1775 1700);
DISPLAY INVISIBLE (-1775 1700);
FORCEADD RES..2
(-7225 2175);
FORCEPROP 1 LAST PACK_TYPE 0402
J 0
(-7185 2000);
DISPLAY 0.617021 (-7185 2000);
PAINT SKYBLUE (-7185 2000);
FORCEPROP 1 LASTPIN (-7225 2075) $PN 2
J 0
(-7220 2085);
DISPLAY 0.617021 (-7220 2085);
PAINT ORANGE (-7220 2085);
FORCEPROP 1 LASTPIN (-7225 2275) $PN 1
J 0
(-7220 2237);
DISPLAY 0.617021 (-7220 2237);
PAINT ORANGE (-7220 2237);
FORCEPROP 1 LAST WATTAGE 1/16W
J 0
(-7185 2150);
DISPLAY 0.617021 (-7185 2150);
PAINT SKYBLUE (-7185 2150);
FORCEPROP 1 LAST MATERIAL CHIP
J 0
(-7185 2100);
DISPLAY 0.617021 (-7185 2100);
PAINT SKYBLUE (-7185 2100);
FORCEPROP 1 LAST TOLERANCE 0.1%
J 0
(-7180 2200);
DISPLAY 0.617021 (-7180 2200);
PAINT SKYBLUE (-7180 2200);
FORCEPROP 1 LAST VALUE 1.0K
J 0
(-7180 2250);
DISPLAY 0.617021 (-7180 2250);
PAINT SKYBLUE (-7180 2250);
FORCEPROP 1 LAST PART_NUMBER G85996-004
J 0
(-7185 2050);
DISPLAY 0.617021 (-7185 2050);
PAINT BLUE (-7185 2050);
FORCEPROP 1 LAST LOCATION R2N4
J 0
(-7180 2300);
DISPLAY 0.617021 (-7180 2300);
PAINT AQUA (-7180 2300);
FORCEPROP 2 LAST CDS_LIB mstr_discrete
J 0
(-7225 2175);
PAINT ORANGE (-7225 2175);
DISPLAY INVISIBLE (-7225 2175);
FORCEPROP 2 LAST CDS_LOCATION R2N4
J 0
(-7180 2300);
DISPLAY 0.617021 (-7180 2300);
PAINT AQUA (-7180 2300);
DISPLAY INVISIBLE (-7180 2300);
FORCEPROP 0 LAST ROOM SB
J 0
(-7175 2400);
DISPLAY 1.021277 (-7175 2400);
PAINT ORANGE (-7175 2400);
DISPLAY INVISIBLE (-7175 2400);
FORCEPROP 1 LAST PATH I96
J 0
(-7175 2350);
DISPLAY 0.978723 (-7175 2350);
PAINT WHITE (-7175 2350);
DISPLAY INVISIBLE (-7175 2350);
FORCEPROP 2 LAST SEC_TYPE 0402
J 0
(-7175 2400);
DISPLAY 1.021277 (-7175 2400);
PAINT ORANGE (-7175 2400);
DISPLAY INVISIBLE (-7175 2400);
FORCEPROP 2 LAST SEC 1
J 0
(-7175 2400);
DISPLAY 0.680851 (-7175 2400);
PAINT MONO (-7175 2400);
DISPLAY INVISIBLE (-7175 2400);
FORCEADD RES..1
(-1700 1875);
FORCEPROP 1 LAST WATTAGE 1/16W
J 2
(-1725 1725);
DISPLAY 0.617021 (-1725 1725);
PAINT SKYBLUE (-1725 1725);
FORCEPROP 1 LAST VALUE 1.0K
J 2
(-1725 1775);
DISPLAY 0.617021 (-1725 1775);
PAINT SKYBLUE (-1725 1775);
FORCEPROP 1 LAST MATERIAL CHIP
J 0
(-1700 1725);
DISPLAY 0.617021 (-1700 1725);
PAINT SKYBLUE (-1700 1725);
FORCEPROP 1 LAST TOLERANCE 0.1%
J 0
(-1700 1775);
DISPLAY 0.617021 (-1700 1775);
PAINT SKYBLUE (-1700 1775);
FORCEPROP 1 LAST LOCATION R2M6
J 0
(-1750 1925);
DISPLAY 0.617021 (-1750 1925);
PAINT AQUA (-1750 1925);
FORCEPROP 1 LASTPIN (-1800 1875) $PN 1
J 0
(-1788 1887);
DISPLAY 0.617021 (-1788 1887);
PAINT ORANGE (-1788 1887);
FORCEPROP 1 LASTPIN (-1600 1875) $PN 2
J 0
(-1638 1887);
DISPLAY 0.617021 (-1638 1887);
PAINT ORANGE (-1638 1887);
FORCEPROP 1 LAST PACK_TYPE 0402
J 0
(-1600 1775);
DISPLAY 0.617021 (-1600 1775);
PAINT SKYBLUE (-1600 1775);
FORCEPROP 1 LAST PART_NUMBER G85996-004
J 0
(-1750 1975);
DISPLAY 0.617021 (-1750 1975);
PAINT BLUE (-1750 1975);
FORCEPROP 2 LAST CDS_LOCATION R2M6
J 0
(-1750 1925);
DISPLAY 0.617021 (-1750 1925);
PAINT AQUA (-1750 1925);
DISPLAY INVISIBLE (-1750 1925);
FORCEPROP 2 LAST CDS_LIB mstr_discrete
J 0
(-1700 1875);
PAINT ORANGE (-1700 1875);
DISPLAY INVISIBLE (-1700 1875);
FORCEPROP 1 LAST PATH I99
J 0
(-1750 2025);
DISPLAY 0.978723 (-1750 2025);
PAINT WHITE (-1750 2025);
DISPLAY INVISIBLE (-1750 2025);
FORCEPROP 0 LAST ROOM SB
J 0
(-1650 2100);
DISPLAY 1.021277 (-1650 2100);
PAINT ORANGE (-1650 2100);
DISPLAY INVISIBLE (-1650 2100);
FORCEPROP 2 LAST SEC_TYPE 0402
J 0
(-1750 2075);
DISPLAY 1.021277 (-1750 2075);
PAINT ORANGE (-1750 2075);
DISPLAY INVISIBLE (-1750 2075);
FORCEPROP 2 LAST SEC 1
J 0
(-1750 2075);
DISPLAY 0.680851 (-1750 2075);
PAINT MONO (-1750 2075);
DISPLAY INVISIBLE (-1750 2075);
FORCEADD DNS..2
(-1670 670);
PAINT RED (-1670 670);
FORCEPROP 1 LAST COMMENT_BODY TRUE
R 1
J 0
(-1595 445);
DISPLAY 0.872340 (-1595 445);
PAINT GREEN (-1595 445);
DISPLAY INVISIBLE (-1595 445);
FORCEPROP 2 LAST CDS_LIB mstr_misc
J 0
(-1670 670);
PAINT ORANGE (-1670 670);
DISPLAY INVISIBLE (-1670 670);
FORCEADD CAD_NOTE..1
(-7175 3725);
FORCEPROP 0 LAST L1 PLACE RST_BMC_SRST# RES CLOSE TO PCH
J 0
(-7325 3600);
DISPLAY 0.936170 (-7325 3600);
PAINT WHITE (-7325 3600);
FORCEPROP 2 LAST ROOM P1V8_PCH_STBY_VR
J 0
(-7325 3675);
DISPLAY 1.659574 (-7325 3675);
PAINT ORANGE (-7325 3675);
DISPLAY INVISIBLE (-7325 3675);
FORCEPROP 2 LAST CDS_LIB mstr_symbols
J 0
(-7175 3725);
PAINT ORANGE (-7175 3725);
DISPLAY INVISIBLE (-7175 3725);
FORCEPROP 1 LAST COMMENT_BODY TRUE
J 0
(-7150 3825);
DISPLAY 2.212766 (-7150 3825);
PAINT PEACH (-7150 3825);
DISPLAY INVISIBLE (-7150 3825);
FORCEADD CAD_NOTE..1
(-6700 550);
FORCEPROP 0 LAST L1 PLACE ON TOP LAYER ONLY
J 0
(-6850 425);
DISPLAY 0.936170 (-6850 425);
PAINT WHITE (-6850 425);
FORCEPROP 1 LAST COMMENT_BODY TRUE
J 0
(-6675 650);
DISPLAY 1.595745 (-6675 650);
PAINT PEACH (-6675 650);
DISPLAY INVISIBLE (-6675 650);
FORCEPROP 2 LAST CDS_LIB mstr_symbols
J 0
(-6700 550);
PAINT MONO (-6700 550);
DISPLAY INVISIBLE (-6700 550);
FORCEADD DNS..2
(-1070 2470);
PAINT RED (-1070 2470);
FORCEPROP 1 LAST COMMENT_BODY TRUE
R 1
J 0
(-995 2245);
DISPLAY 0.872340 (-995 2245);
PAINT GREEN (-995 2245);
DISPLAY INVISIBLE (-995 2245);
FORCEPROP 2 LAST CDS_LIB mstr_misc
J 0
(-1070 2470);
PAINT ORANGE (-1070 2470);
DISPLAY INVISIBLE (-1070 2470);
FORCEADD CAD_NOTE..1
(-1275 1775);
FORCEPROP 0 LAST L1 MUST PLACE LAN_BIAS RES
J 0
(-1425 1650);
DISPLAY 0.936170 (-1425 1650);
PAINT WHITE (-1425 1650);
FORCEPROP 0 LAST L2 WITHIN 3 INCHES OF PCH
J 0
(-1425 1575);
DISPLAY 0.936170 (-1425 1575);
PAINT WHITE (-1425 1575);
FORCEPROP 2 LAST ROOM P1V8_PCH_STBY_VR
J 0
(-1425 1725);
DISPLAY 1.659574 (-1425 1725);
PAINT ORANGE (-1425 1725);
DISPLAY INVISIBLE (-1425 1725);
FORCEPROP 1 LAST COMMENT_BODY TRUE
J 0
(-1250 1875);
DISPLAY 2.212766 (-1250 1875);
PAINT PEACH (-1250 1875);
DISPLAY INVISIBLE (-1250 1875);
FORCEPROP 2 LAST CDS_LIB mstr_symbols
J 0
(-1275 1775);
PAINT ORANGE (-1275 1775);
DISPLAY INVISIBLE (-1275 1775);
FORCEADD CAD_NOTE..1
(-7575 1800);
FORCEPROP 0 LAST L1 MUST PLACE LAN_RBIAS RES
J 0
(-7725 1675);
DISPLAY 0.936170 (-7725 1675);
PAINT WHITE (-7725 1675);
FORCEPROP 0 LAST L2 WITHIN 3 INCHES OF PCH
J 0
(-7725 1600);
DISPLAY 0.936170 (-7725 1600);
PAINT WHITE (-7725 1600);
FORCEPROP 2 LAST ROOM P1V8_PCH_STBY_VR
J 0
(-7725 1750);
DISPLAY 1.659574 (-7725 1750);
PAINT ORANGE (-7725 1750);
DISPLAY INVISIBLE (-7725 1750);
FORCEPROP 2 LAST CDS_LIB mstr_symbols
J 0
(-7575 1800);
PAINT ORANGE (-7575 1800);
DISPLAY INVISIBLE (-7575 1800);
FORCEPROP 1 LAST COMMENT_BODY TRUE
J 0
(-7550 1900);
DISPLAY 2.212766 (-7550 1900);
PAINT PEACH (-7550 1900);
DISPLAY INVISIBLE (-7550 1900);
FORCEADD CAD_NOTE..1
(-4775 625);
FORCEPROP 0 LAST L1 PLACE CAP CLOSE TO VCC PIN
J 0
(-4925 500);
DISPLAY 1.021277 (-4925 500);
PAINT ORANGE (-4925 500);
FORCEPROP 1 LAST COMMENT_BODY TRUE
J 0
(-4750 725);
DISPLAY 0.978723 (-4750 725);
PAINT ORANGE (-4750 725);
DISPLAY INVISIBLE (-4750 725);
FORCEPROP 2 LAST CDS_LIB mstr_symbols
J 0
(-4775 625);
PAINT ORANGE (-4775 625);
DISPLAY INVISIBLE (-4775 625);
FORCEADD INTEL_CORP_BPAGE..1
(0 0);
FORCEPROP 1 LAST CDS_CON_LAST_MODIFIED Tue Dec 01 11:51:57 2015
J 0
(-1425 325);
DISPLAY 1.340426 (-1425 325);
PAINT ORANGE (-1425 325);
DISPLAY INVISIBLE (-1425 325);
FORCEPROP 1 LAST CUSTOM_TXT_CDS <CURRENT_DESIGN_SHEET> OF <TOTAL_DESIGN_SHEETS>
J 0
(-500 25);
PAINT GREEN (-500 25);
FORCEPROP 1 LAST CUSTOM_TXT_CDS <CON_LAST_MODIFIED>
J 0
(-1925 350);
PAINT GREEN (-1925 350);
FORCEPROP 2 LAST CUSTOM_TXT_CDS <XR_PAGE_TITLE>
J 0
(-7890 5250);
DISPLAY 0.638298 (-7890 5250);
PAINT PINK (-7890 5250);
DISPLAY INVISIBLE (-7890 5250);
FORCEPROP 1 LAST SCH_TITLE LEWISBURG 5/11 LAN
J 0
(-7950 50);
DISPLAY 1.212766 (-7950 50);
PAINT YELLOW (-7950 50);
FORCEPROP 1 LAST SCH_ADDRESS1 2200 Mission College Blvd.
J 0
(-3975 125);
DISPLAY 0.617021 (-3975 125);
PAINT YELLOW (-3975 125);
FORCEPROP 1 LAST SCH_ADDRESS2 P.O. BOX 58119
J 0
(-3975 75);
DISPLAY 0.617021 (-3975 75);
PAINT YELLOW (-3975 75);
FORCEPROP 1 LAST SCH_ADDRESS3 Santa Clara, CA 95052-8119
J 0
(-3975 25);
DISPLAY 0.617021 (-3975 25);
PAINT YELLOW (-3975 25);
FORCEPROP 1 LAST SCH_REV 2.420
J 0
(-250 150);
DISPLAY 0.978723 (-250 150);
PAINT YELLOW (-250 150);
FORCEPROP 1 LAST SCH_DEPT BESD
J 1
(-4450 100);
DISPLAY 1.212766 (-4450 100);
PAINT YELLOW (-4450 100);
FORCEPROP 1 LAST SCH_NUMBER H4694802
J 0
(-1300 150);
DISPLAY 1.212766 (-1300 150);
PAINT YELLOW (-1300 150);
FORCEPROP 2 LAST PAGE_BORDER TRUE
J 0
(-7890 5250);
DISPLAY 0.851064 (-7890 5250);
PAINT PINK (-7890 5250);
DISPLAY INVISIBLE (-7890 5250);
FORCEPROP 2 LAST CDS_LIB mstr_symbols
J 0
(0 0);
PAINT ORANGE (0 0);
DISPLAY INVISIBLE (0 0);
FORCEPROP 1 LAST COMMENT_BODY TRUE
J 0
(12 12);
DISPLAY 0.638298 (12 12);
PAINT PEACH (12 12);
DISPLAY INVISIBLE (12 12);
FORCEPROP 2 LAST CDS_XR_PAGE_TITLE CR-118 : @BASEBOARD_FAB2_LIB.BASEBOARD_FAB2(SCH_1):PAGE118
J 0
(-7890 5250);
DISPLAY 0.638298 (-7890 5250);
PAINT PINK (-7890 5250);
DISPLAY INVISIBLE (-7890 5250);
WIRE 16 -1 (-1000 1975)(-1000 1875);
WIRE 16 -1 (-1000 1875)(-1600 1875);
WIRE 16 -1 (-7225 2275)(-7225 2350);
WIRE 16 -1 (-2200 1200)(-2200 1225);
WIRE 16 -1 (-5200 475)(-5200 575);
WIRE 16 -1 (-5200 175)(-5200 275);
WIRE 16 -1 (-5175 1375)(-5175 1400);
WIRE 16 -1 (-1075 2375)(-1075 2275);
WIRE 16 -1 (-2300 4750)(-2300 4825);
WIRE 16 -1 (-7250 450)(-7250 500);
WIRE 16 -1 (-7700 475)(-7700 525);
WIRE 16 -1 (-1975 4175)(-2300 4175);
WIRE 16 -1 (-2300 4550)(-2300 4175);
WIRE 16 -1 (-2300 4175)(-3125 4175);
FORCEPROP 2 LAST SIG_NAME IRQ_LVC3_WAKE_N
J 0
(-2935 4185);
DISPLAY 0.617021 (-2935 4185);
PAINT ORANGE (-2935 4185);
WIRE 16 -1 (-1975 4125)(-3125 4125);
FORCEPROP 2 LAST SIG_NAME FM_SLP_SUS_N
J 0
(-2935 4135);
DISPLAY 0.617021 (-2935 4135);
PAINT ORANGE (-2935 4135);
WIRE 16 -1 (-3125 4275)(-1975 4275);
FORCEPROP 2 LAST SIG_NAME PWRGD_SYS_PWROK
J 0
(-2935 4285);
DISPLAY 0.617021 (-2935 4285);
PAINT ORANGE (-2935 4285);
WIRE 16 -1 (-3125 4425)(-1975 4425);
FORCEPROP 2 LAST SIG_NAME PWRGD_CPUPWRGD_GTL
J 0
(-2935 4435);
DISPLAY 0.617021 (-2935 4435);
PAINT ORANGE (-2935 4435);
WIRE 16 -1 (-3125 4375)(-1975 4375);
FORCEPROP 2 LAST SIG_NAME PWRGD_DSW_PWROK
J 0
(-2935 4385);
DISPLAY 0.617021 (-2935 4385);
PAINT ORANGE (-2935 4385);
WIRE 16 -1 (-3125 4325)(-1975 4325);
FORCEPROP 2 LAST SIG_NAME PWRGD_PCH_PWROK
J 0
(-2935 4335);
DISPLAY 0.617021 (-2935 4335);
PAINT ORANGE (-2935 4335);
WIRE 16 -1 (-650 2675)(-1075 2675);
FORCEPROP 2 LAST SIG_NAME H_PM_SYNC_GTL
J 0
(-1060 2685);
DISPLAY 0.617021 (-1060 2685);
PAINT ORANGE (-1060 2685);
WIRE 16 -1 (-1075 2675)(-1075 2575);
WIRE 16 -1 (-1475 2675)(-1075 2675);
WIRE 16 -1 (-1575 900)(-875 900);
FORCEPROP 2 LAST SIG_NAME FM_1GB_LOM_DISABLE_N
J 0
(-1385 910);
DISPLAY 0.617021 (-1385 910);
PAINT ORANGE (-1385 910);
WIRE 16 -1 (-1575 675)(-875 675);
FORCEPROP 2 LAST SIG_NAME FM_10GBE_LOM_DISABLE_N
J 0
(-1385 685);
DISPLAY 0.617021 (-1385 685);
PAINT ORANGE (-1385 685);
WIRE 16 -1 (-1925 675)(-1775 675);
WIRE 16 -1 (-1925 900)(-1925 675);
WIRE 16 -1 (-1775 900)(-1925 900);
WIRE 16 -1 (-1925 900)(-2200 900);
WIRE 16 -1 (-2200 900)(-2200 1000);
WIRE 16 -1 (-2200 900)(-2850 900);
FORCEPROP 2 LAST SIG_NAME FM_GBE_LOM_DISABLE_N
J 0
(-2810 910);
DISPLAY 0.617021 (-2810 910);
PAINT ORANGE (-2810 910);
WIRE 16 -1 (-3125 1875)(-1800 1875);
FORCEPROP 0 LAST SIG_NAME A_KR1_RBIAS
J 0
(-2535 1885);
DISPLAY 0.617021 (-2535 1885);
PAINT ORANGE (-2535 1885);
FORCEPROP 2 LASTPROP $XRERR UNIQUE?
J 0
(-2775 1885);
DISPLAY 0.638298 (-2775 1885);
PAINT MONO (-2775 1885);
DISPLAY INVISIBLE (-2775 1885);
WIRE 16 -1 (-3125 2675)(-1675 2675);
FORCEPROP 2 LAST SIG_NAME H_PM_SYNC1_GTL_R
J 0
(-2535 2675);
DISPLAY 0.617021 (-2535 2675);
PAINT ORANGE (-2535 2675);
FORCEPROP 2 LASTPROP $XRERR UNIQUE?
J 0
(-2775 2675);
DISPLAY 0.638298 (-2775 2675);
PAINT MONO (-2775 2675);
DISPLAY INVISIBLE (-2775 2675);
WIRE 16 -1 (-1975 4075)(-3125 4075);
FORCEPROP 2 LAST SIG_NAME TP_SLP_LAN_N
J 0
(-2935 4085);
DISPLAY 0.617021 (-2935 4085);
PAINT ORANGE (-2935 4085);
FORCEPROP 2 LASTPROP $XRERR UNIQUE?
J 0
(-1945 4075);
DISPLAY 0.638298 (-1945 4075);
PAINT MONO (-1945 4075);
DISPLAY INVISIBLE (-1945 4075);
WIRE 16 -1 (-1975 4025)(-3125 4025);
FORCEPROP 2 LAST SIG_NAME RST_RSMRST_N
J 0
(-2935 4035);
DISPLAY 0.617021 (-2935 4035);
PAINT ORANGE (-2935 4035);
WIRE 16 -1 (-1975 3875)(-3125 3875);
FORCEPROP 2 LAST SIG_NAME RST_BMC_SYSRST_BTN_OUT_B_N
J 0
(-2935 3885);
DISPLAY 0.617021 (-2935 3885);
PAINT ORANGE (-2935 3885);
WIRE 16 -1 (-1975 2825)(-3125 2825);
FORCEPROP 2 LAST SIG_NAME FM_PCH_LVC1_THERMTRIP_N
J 0
(-2535 2825);
DISPLAY 0.617021 (-2535 2825);
PAINT ORANGE (-2535 2825);
WIRE 16 -1 (-1975 2775)(-3125 2775);
FORCEPROP 2 LAST SIG_NAME PECI_PCH
J 0
(-2535 2775);
DISPLAY 0.617021 (-2535 2775);
PAINT ORANGE (-2535 2775);
WIRE 16 -1 (-2000 1625)(-3125 1625);
FORCEPROP 2 LAST SIG_NAME XTAL_KR_25M_OUT
J 0
(-2535 1635);
DISPLAY 0.617021 (-2535 1635);
PAINT ORANGE (-2535 1635);
WIRE 16 -1 (-2375 3925)(-3125 3925);
FORCEPROP 2 LAST SIG_NAME TP_PLTRST_CPU_N
J 0
(-2935 3935);
DISPLAY 0.617021 (-2935 3935);
PAINT ORANGE (-2935 3935);
FORCEPROP 2 LASTPROP $XRERR UNIQUE?
J 0
(-2345 3925);
DISPLAY 0.638298 (-2345 3925);
PAINT MONO (-2345 3925);
DISPLAY INVISIBLE (-2345 3925);
WIRE 16 -1 (-2575 2625)(-3125 2625);
FORCEPROP 2 LAST SIG_NAME TP_PM_SYNC_GTL
J 0
(-2975 2635);
DISPLAY 0.617021 (-2975 2635);
PAINT ORANGE (-2975 2635);
FORCEPROP 2 LASTPROP $XRERR UNIQUE?
J 0
(-2545 2625);
DISPLAY 0.638298 (-2545 2625);
PAINT MONO (-2545 2625);
DISPLAY INVISIBLE (-2545 2625);
WIRE 16 -1 (-3125 2925)(-2575 2925);
FORCEPROP 2 LAST SIG_NAME TP_PCH_RSVD54
J 0
(-2975 2935);
DISPLAY 0.617021 (-2975 2935);
PAINT ORANGE (-2975 2935);
FORCEPROP 2 LASTPROP $XRERR UNIQUE?
J 0
(-2545 2925);
DISPLAY 0.638298 (-2545 2925);
PAINT MONO (-2545 2925);
DISPLAY INVISIBLE (-2545 2925);
WIRE 16 -1 (-3125 2975)(-2575 2975);
FORCEPROP 2 LAST SIG_NAME TP_PCH_RSVD53
J 0
(-2975 2985);
DISPLAY 0.617021 (-2975 2985);
PAINT ORANGE (-2975 2985);
FORCEPROP 2 LASTPROP $XRERR UNIQUE?
J 0
(-2545 2975);
DISPLAY 0.638298 (-2545 2975);
PAINT MONO (-2545 2975);
DISPLAY INVISIBLE (-2545 2975);
WIRE 16 -1 (-3125 2475)(-2575 2475);
FORCEPROP 0 LAST SIG_NAME KR_P3_OCP_TX_DP
J 0
(-2950 2485);
DISPLAY 0.617021 (-2950 2485);
PAINT ORANGE (-2950 2485);
WIRE 16 -1 (-3125 2425)(-2575 2425);
FORCEPROP 0 LAST SIG_NAME KR_P3_OCP_TX_DN
J 0
(-2950 2435);
DISPLAY 0.617021 (-2950 2435);
PAINT ORANGE (-2950 2435);
WIRE 16 -1 (-2575 2375)(-3125 2375);
FORCEPROP 0 LAST SIG_NAME KR_P2_OCP_TX_DP
J 0
(-2950 2385);
DISPLAY 0.617021 (-2950 2385);
PAINT ORANGE (-2950 2385);
WIRE 16 -1 (-2575 2325)(-3125 2325);
FORCEPROP 0 LAST SIG_NAME KR_P2_OCP_TX_DN
J 0
(-2950 2335);
DISPLAY 0.617021 (-2950 2335);
PAINT ORANGE (-2950 2335);
WIRE 16 -1 (-3125 2225)(-2575 2225);
FORCEPROP 0 LAST SIG_NAME KR_P1_OCP_TX_DP
J 0
(-2950 2235);
DISPLAY 0.617021 (-2950 2235);
PAINT ORANGE (-2950 2235);
WIRE 16 -1 (-3125 2175)(-2575 2175);
FORCEPROP 0 LAST SIG_NAME KR_P1_OCP_TX_DN
J 0
(-2950 2185);
DISPLAY 0.617021 (-2950 2185);
PAINT ORANGE (-2950 2185);
WIRE 16 -1 (-3125 2125)(-2575 2125);
FORCEPROP 0 LAST SIG_NAME KR_P0_OCP_TX_DP
J 0
(-2950 2135);
DISPLAY 0.617021 (-2950 2135);
PAINT ORANGE (-2950 2135);
WIRE 16 -1 (-3125 2075)(-2575 2075);
FORCEPROP 0 LAST SIG_NAME KR_P0_OCP_TX_DN
J 0
(-2950 2085);
DISPLAY 0.617021 (-2950 2085);
PAINT ORANGE (-2950 2085);
WIRE 16 -1 (-3125 1975)(-2575 1975);
FORCEPROP 2 LAST SIG_NAME TP_10GBE_KR1_MON_DP
J 0
(-2975 1985);
DISPLAY 0.617021 (-2975 1985);
PAINT ORANGE (-2975 1985);
FORCEPROP 2 LASTPROP $XRERR UNIQUE?
J 0
(-2545 1975);
DISPLAY 0.638298 (-2545 1975);
PAINT MONO (-2545 1975);
DISPLAY INVISIBLE (-2545 1975);
WIRE 16 -1 (-3125 1925)(-2575 1925);
FORCEPROP 2 LAST SIG_NAME TP_10GBE_KR1_MON_DN
J 0
(-2975 1935);
DISPLAY 0.617021 (-2975 1935);
PAINT ORANGE (-2975 1935);
FORCEPROP 2 LASTPROP $XRERR UNIQUE?
J 0
(-2545 1925);
DISPLAY 0.638298 (-2545 1925);
PAINT MONO (-2545 1925);
DISPLAY INVISIBLE (-2545 1925);
WIRE 16 -1 (-3125 1775)(-2575 1775);
FORCEPROP 2 LAST SIG_NAME TP_PCH_RSVD42
J 0
(-2975 1785);
DISPLAY 0.617021 (-2975 1785);
PAINT ORANGE (-2975 1785);
FORCEPROP 2 LASTPROP $XRERR UNIQUE?
J 0
(-2545 1775);
DISPLAY 0.638298 (-2545 1775);
PAINT MONO (-2545 1775);
DISPLAY INVISIBLE (-2545 1775);
WIRE 16 -1 (-3125 1725)(-2575 1725);
FORCEPROP 2 LAST SIG_NAME TP_PCH_RSVD41
J 0
(-2975 1735);
DISPLAY 0.617021 (-2975 1735);
PAINT ORANGE (-2975 1735);
FORCEPROP 2 LASTPROP $XRERR UNIQUE?
J 0
(-2545 1725);
DISPLAY 0.638298 (-2545 1725);
PAINT MONO (-2545 1725);
DISPLAY INVISIBLE (-2545 1725);
WIRE 16 -1 (-4325 1075)(-3700 1075);
FORCEPROP 0 LAST SIG_NAME XDP_CPU_PWR_DEBUG_N
J 0
(-4260 1085);
DISPLAY 0.617021 (-4260 1085);
PAINT ORANGE (-4260 1085);
WIRE 16 -1 (-5725 4425)(-4925 4425);
FORCEPROP 2 LAST SIG_NAME FM_GBE_LOM_DISABLE_N
J 0
(-5725 4435);
DISPLAY 0.617021 (-5725 4435);
PAINT ORANGE (-5725 4435);
WIRE 16 -1 (-5725 4375)(-4925 4375);
FORCEPROP 0 LAST SIG_NAME FM_CPU0_RC_ERROR_N
J 0
(-5725 4386);
DISPLAY 0.617021 (-5725 4386);
PAINT ORANGE (-5725 4386);
WIRE 16 -1 (-5725 4325)(-4925 4325);
FORCEPROP 2 LAST SIG_NAME FM_BMC_CPLD_MP_RST_N
J 0
(-5725 4335);
DISPLAY 0.617021 (-5725 4335);
PAINT ORANGE (-5725 4335);
WIRE 16 -1 (-5725 4275)(-4925 4275);
FORCEPROP 2 LAST SIG_NAME IRQ_SML1_PMBUS_ALERT_N
J 0
(-5725 4285);
DISPLAY 0.617021 (-5725 4285);
PAINT ORANGE (-5725 4285);
WIRE 16 -1 (-5725 4225)(-4925 4225);
FORCEPROP 2 LAST SIG_NAME FM_BATTERY_SENSE_EN_N
J 0
(-5725 4235);
DISPLAY 0.617021 (-5725 4235);
PAINT ORANGE (-5725 4235);
WIRE 16 -1 (-5725 4175)(-4925 4175);
FORCEPROP 2 LAST SIG_NAME FM_CPU0_SKTOCC_LVT3_N
J 0
(-5725 4185);
DISPLAY 0.617021 (-5725 4185);
PAINT ORANGE (-5725 4185);
WIRE 16 -1 (-5725 4125)(-4925 4125);
FORCEPROP 2 LAST SIG_NAME FM_SLPS4_N
J 0
(-5725 4135);
DISPLAY 0.617021 (-5725 4135);
PAINT ORANGE (-5725 4135);
WIRE 16 -1 (-5725 4075)(-4925 4075);
FORCEPROP 2 LAST SIG_NAME FM_SLPS3_N
J 0
(-5725 4085);
DISPLAY 0.617021 (-5725 4085);
PAINT ORANGE (-5725 4085);
WIRE 16 -1 (-5725 4025)(-4925 4025);
FORCEPROP 2 LAST SIG_NAME FM_PCH_PWRBTN_N
J 0
(-5725 4035);
DISPLAY 0.617021 (-5725 4035);
PAINT ORANGE (-5725 4035);
WIRE 16 -1 (-5725 3925)(-4925 3925);
FORCEPROP 2 LAST SIG_NAME FM_CPU1_SKTOCC_LVT3_N
J 0
(-5725 3935);
DISPLAY 0.617021 (-5725 3935);
PAINT ORANGE (-5725 3935);
WIRE 16 -1 (-5725 3875)(-4925 3875);
FORCEPROP 2 LAST SIG_NAME XDP_PCH_PWR_DEBUG_N
J 0
(-5725 3885);
DISPLAY 0.617021 (-5725 3885);
PAINT ORANGE (-5725 3885);
WIRE 16 -1 (-5575 3625)(-4925 3625);
FORCEPROP 2 LAST SIG_NAME TP_PCH_RSVD32
J 0
(-5550 3635);
DISPLAY 0.617021 (-5550 3635);
PAINT ORANGE (-5550 3635);
FORCEPROP 2 LASTPROP $XRERR UNIQUE?
J 0
(-5815 3625);
DISPLAY 0.638298 (-5815 3625);
PAINT MONO (-5815 3625);
DISPLAY INVISIBLE (-5815 3625);
WIRE 16 -1 (-5575 3575)(-4925 3575);
FORCEPROP 2 LAST SIG_NAME TP_PCH_RSVD33
J 0
(-5550 3585);
DISPLAY 0.617021 (-5550 3585);
PAINT ORANGE (-5550 3585);
FORCEPROP 2 LASTPROP $XRERR UNIQUE?
J 0
(-5815 3575);
DISPLAY 0.638298 (-5815 3575);
PAINT MONO (-5815 3575);
DISPLAY INVISIBLE (-5815 3575);
WIRE 16 -1 (-5575 3775)(-4925 3775);
FORCEPROP 2 LAST SIG_NAME TP_PCH_RSVD45
J 0
(-5550 3785);
DISPLAY 0.617021 (-5550 3785);
PAINT ORANGE (-5550 3785);
FORCEPROP 2 LASTPROP $XRERR UNIQUE?
J 0
(-5815 3775);
DISPLAY 0.638298 (-5815 3775);
PAINT MONO (-5815 3775);
DISPLAY INVISIBLE (-5815 3775);
WIRE 16 -1 (-5575 3425)(-4925 3425);
FORCEPROP 2 LAST SIG_NAME TP_PCH_RSVD36
J 0
(-5550 3435);
DISPLAY 0.617021 (-5550 3435);
PAINT ORANGE (-5550 3435);
FORCEPROP 2 LASTPROP $XRERR UNIQUE?
J 0
(-5815 3425);
DISPLAY 0.638298 (-5815 3425);
PAINT MONO (-5815 3425);
DISPLAY INVISIBLE (-5815 3425);
WIRE 16 -1 (-5575 3475)(-4925 3475);
FORCEPROP 2 LAST SIG_NAME TP_PCH_RSVD35
J 0
(-5550 3485);
DISPLAY 0.617021 (-5550 3485);
PAINT ORANGE (-5550 3485);
FORCEPROP 2 LASTPROP $XRERR UNIQUE?
J 0
(-5815 3475);
DISPLAY 0.638298 (-5815 3475);
PAINT MONO (-5815 3475);
DISPLAY INVISIBLE (-5815 3475);
WIRE 16 -1 (-5575 3525)(-4925 3525);
FORCEPROP 2 LAST SIG_NAME TP_PCH_RSVD34
J 0
(-5550 3535);
DISPLAY 0.617021 (-5550 3535);
PAINT ORANGE (-5550 3535);
FORCEPROP 2 LASTPROP $XRERR UNIQUE?
J 0
(-5815 3525);
DISPLAY 0.638298 (-5815 3525);
PAINT MONO (-5815 3525);
DISPLAY INVISIBLE (-5815 3525);
WIRE 16 -1 (-5575 3325)(-4925 3325);
FORCEPROP 2 LAST SIG_NAME TP_CPU_PCH_TRIGGER_IN
J 0
(-5550 3335);
DISPLAY 0.617021 (-5550 3335);
PAINT ORANGE (-5550 3335);
FORCEPROP 2 LASTPROP $XRERR UNIQUE?
J 0
(-5815 3325);
DISPLAY 0.638298 (-5815 3325);
PAINT MONO (-5815 3325);
DISPLAY INVISIBLE (-5815 3325);
WIRE 16 -1 (-5575 3275)(-4925 3275);
FORCEPROP 2 LAST SIG_NAME TP_CPU_PCH_TRIGGER_OUT
J 0
(-5550 3285);
DISPLAY 0.617021 (-5550 3285);
PAINT ORANGE (-5550 3285);
FORCEPROP 2 LASTPROP $XRERR UNIQUE?
J 0
(-5815 3275);
DISPLAY 0.638298 (-5815 3275);
PAINT MONO (-5815 3275);
DISPLAY INVISIBLE (-5815 3275);
WIRE 16 -1 (-5600 2475)(-4925 2475);
FORCEPROP 0 LAST SIG_NAME KR_P3_OCP_RX_C_DP
J 0
(-5575 2485);
DISPLAY 0.617021 (-5575 2485);
PAINT ORANGE (-5575 2485);
WIRE 16 -1 (-5600 2425)(-4925 2425);
FORCEPROP 0 LAST SIG_NAME KR_P3_OCP_RX_C_DN
J 0
(-5575 2435);
DISPLAY 0.617021 (-5575 2435);
PAINT ORANGE (-5575 2435);
WIRE 16 -1 (-5600 2375)(-4925 2375);
FORCEPROP 0 LAST SIG_NAME KR_P2_OCP_RX_C_DP
J 0
(-5575 2385);
DISPLAY 0.617021 (-5575 2385);
PAINT ORANGE (-5575 2385);
WIRE 16 -1 (-5600 2325)(-4925 2325);
FORCEPROP 0 LAST SIG_NAME KR_P2_OCP_RX_C_DN
J 0
(-5575 2335);
DISPLAY 0.617021 (-5575 2335);
PAINT ORANGE (-5575 2335);
WIRE 16 -1 (-5600 2225)(-4925 2225);
FORCEPROP 0 LAST SIG_NAME KR_P1_OCP_RX_C_DP
J 0
(-5575 2235);
DISPLAY 0.617021 (-5575 2235);
PAINT ORANGE (-5575 2235);
WIRE 16 -1 (-5600 2175)(-4925 2175);
FORCEPROP 0 LAST SIG_NAME KR_P1_OCP_RX_C_DN
J 0
(-5575 2185);
DISPLAY 0.617021 (-5575 2185);
PAINT ORANGE (-5575 2185);
WIRE 16 -1 (-5600 2125)(-4925 2125);
FORCEPROP 0 LAST SIG_NAME KR_P0_OCP_RX_C_DP
J 0
(-5575 2135);
DISPLAY 0.617021 (-5575 2135);
PAINT ORANGE (-5575 2135);
WIRE 16 -1 (-5600 2075)(-4925 2075);
FORCEPROP 0 LAST SIG_NAME KR_P0_OCP_RX_C_DN
J 0
(-5575 2085);
DISPLAY 0.617021 (-5575 2085);
PAINT ORANGE (-5575 2085);
WIRE 16 -1 (-5625 3175)(-4925 3175);
FORCEPROP 2 LAST SIG_NAME XDP_PCH_TCK1
J 0
(-5625 3185);
DISPLAY 0.617021 (-5625 3185);
PAINT ORANGE (-5625 3185);
WIRE 16 -1 (-5625 3125)(-4925 3125);
FORCEPROP 2 LAST SIG_NAME XDP_TDI
J 0
(-5625 3135);
DISPLAY 0.617021 (-5625 3135);
PAINT ORANGE (-5625 3135);
WIRE 16 -1 (-5625 3075)(-4925 3075);
FORCEPROP 2 LAST SIG_NAME XDP_TDO
J 0
(-5625 3085);
DISPLAY 0.617021 (-5625 3085);
PAINT ORANGE (-5625 3085);
WIRE 16 -1 (-5625 3025)(-4925 3025);
FORCEPROP 2 LAST SIG_NAME XDP_TMS
J 0
(-5625 3035);
DISPLAY 0.617021 (-5625 3035);
PAINT ORANGE (-5625 3035);
WIRE 16 -1 (-5650 2975)(-4925 2975);
FORCEPROP 2 LAST SIG_NAME XDP_PCH_CPU_TCK0
J 0
(-5625 2985);
DISPLAY 0.617021 (-5625 2985);
PAINT ORANGE (-5625 2985);
WIRE 16 -1 (-5625 2825)(-4925 2825);
FORCEPROP 2 LAST SIG_NAME XDP_PRDY_N
J 0
(-5625 2835);
DISPLAY 0.617021 (-5625 2835);
PAINT ORANGE (-5625 2835);
WIRE 16 -1 (-5625 2725)(-4925 2725);
FORCEPROP 2 LAST SIG_NAME XDP_ITP_PMODE
J 0
(-5625 2735);
DISPLAY 0.617021 (-5625 2735);
PAINT ORANGE (-5625 2735);
WIRE 16 -1 (-5625 2675)(-4925 2675);
FORCEPROP 2 LAST SIG_NAME XDP_TRST_N
J 0
(-5625 2685);
DISPLAY 0.617021 (-5625 2685);
PAINT ORANGE (-5625 2685);
WIRE 16 -1 (-5625 2875)(-4925 2875);
FORCEPROP 2 LAST SIG_NAME XDP_PREQ_N
J 0
(-5625 2885);
DISPLAY 0.617021 (-5625 2885);
PAINT ORANGE (-5625 2885);
WIRE 16 -1 (-5175 1175)(-5175 1075);
WIRE 16 -1 (-4825 1075)(-5175 1075);
WIRE 16 -1 (-5750 1075)(-5175 1075);
FORCEPROP 0 LAST SIG_NAME XDP_PCH_PWR_DEBUG_N
J 0
(-5710 1085);
DISPLAY 0.617021 (-5710 1085);
PAINT ORANGE (-5710 1085);
WIRE 16 -1 (-5600 1975)(-4925 1975);
FORCEPROP 2 LAST SIG_NAME TP_10GBE_KR0_MON_DP
J 0
(-5550 1985);
DISPLAY 0.617021 (-5550 1985);
PAINT ORANGE (-5550 1985);
FORCEPROP 2 LASTPROP $XRERR UNIQUE?
J 0
(-5840 1975);
DISPLAY 0.638298 (-5840 1975);
PAINT MONO (-5840 1975);
DISPLAY INVISIBLE (-5840 1975);
WIRE 16 -1 (-5600 1925)(-4925 1925);
FORCEPROP 2 LAST SIG_NAME TP_10GBE_KR0_MON_DN
J 0
(-5550 1935);
DISPLAY 0.617021 (-5550 1935);
PAINT ORANGE (-5550 1935);
FORCEPROP 2 LASTPROP $XRERR UNIQUE?
J 0
(-5840 1925);
DISPLAY 0.638298 (-5840 1925);
PAINT MONO (-5840 1925);
DISPLAY INVISIBLE (-5840 1925);
WIRE 16 -1 (-5600 1775)(-4925 1775);
FORCEPROP 2 LAST SIG_NAME TP_PCH_RSVD38
J 0
(-5550 1785);
DISPLAY 0.617021 (-5550 1785);
PAINT ORANGE (-5550 1785);
FORCEPROP 2 LASTPROP $XRERR UNIQUE?
J 0
(-5840 1775);
DISPLAY 0.638298 (-5840 1775);
PAINT MONO (-5840 1775);
DISPLAY INVISIBLE (-5840 1775);
WIRE 16 -1 (-5600 1725)(-4925 1725);
FORCEPROP 2 LAST SIG_NAME TP_PCH_RSVD37
J 0
(-5550 1735);
DISPLAY 0.617021 (-5550 1735);
PAINT ORANGE (-5550 1735);
FORCEPROP 2 LASTPROP $XRERR UNIQUE?
J 0
(-5840 1725);
DISPLAY 0.638298 (-5840 1725);
PAINT MONO (-5840 1725);
DISPLAY INVISIBLE (-5840 1725);
WIRE 16 -1 (-4825 1025)(-5750 1025);
FORCEPROP 0 LAST SIG_NAME PWRGD_PVCCIO_CPU0
J 0
(-5710 1035);
DISPLAY 0.617021 (-5710 1035);
PAINT ORANGE (-5710 1035);
WIRE 16 -1 (-4925 1625)(-5625 1625);
FORCEPROP 2 LAST SIG_NAME XTAL_KR_25M_IN
J 0
(-5625 1635);
DISPLAY 0.617021 (-5625 1635);
PAINT ORANGE (-5625 1635);
WIRE 16 -1 (-6650 3975)(-4925 3975);
FORCEPROP 2 LAST SIG_NAME RST_BMC_SRST_R_N
J 0
(-5725 3985);
DISPLAY 0.617021 (-5725 3985);
PAINT ORANGE (-5725 3985);
FORCEPROP 2 LASTPROP $XRERR UNIQUE?
J 0
(-5965 3985);
DISPLAY 0.638298 (-5965 3985);
PAINT MONO (-5965 3985);
DISPLAY INVISIBLE (-5965 3985);
WIRE 16 -1 (-4925 1875)(-7225 1875);
FORCEPROP 0 LAST SIG_NAME A_KR0_RBIAS
J 0
(-6175 1875);
DISPLAY 0.617021 (-6175 1875);
PAINT ORANGE (-6175 1875);
FORCEPROP 2 LASTPROP $XRERR UNIQUE?
J 0
(-6415 1875);
DISPLAY 0.638298 (-6415 1875);
PAINT MONO (-6415 1875);
DISPLAY INVISIBLE (-6415 1875);
WIRE 16 -1 (-7225 2075)(-7225 1875);
WIRE 16 -1 (-7325 3975)(-6850 3975);
FORCEPROP 0 LAST SIG_NAME RST_BMC_SRST_N
J 0
(-7310 3985);
DISPLAY 0.617021 (-7310 3985);
PAINT ORANGE (-7310 3985);
WIRE 16 -1 (-7250 850)(-6800 850);
FORCEPROP 2 LAST SIG_NAME XTAL_KR_25M_OUT
J 0
(-7160 860);
DISPLAY 0.617021 (-7160 860);
PAINT ORANGE (-7160 860);
WIRE 16 -1 (-7250 850)(-7300 850);
WIRE 16 -1 (-7250 700)(-7250 850);
WIRE 16 -1 (-7700 1150)(-7175 1150);
WIRE 16 -1 (-7700 850)(-7700 1150);
FORCEPROP 2 LAST SIG_NAME XTAL_KR_25M_IN
J 0
(-7710 1160);
DISPLAY 0.617021 (-7710 1160);
PAINT ORANGE (-7710 1160);
WIRE 16 -1 (-7700 850)(-7500 850);
WIRE 16 -1 (-7700 725)(-7700 850);
DOT 1 (-7700 850);
DOT 1 (-7250 850);
DOT 1 (-5175 1075);
DOT 1 (-2200 900);
DOT 1 (-1925 900);
DOT 1 (-1075 2675);
DOT 1 (-2300 4175);
FORCENOTE
BOM_COST=SB
(-6775 125) 0;
DISPLAY LEFT (-6775 125);
DISPLAY 1.021277 (-6775 125);
PAINT PURPLE (-6775 125);
FORCENOTE
ROOM-SB
(-6775 175) 0;
DISPLAY LEFT (-6775 175);
DISPLAY 1.021277 (-6775 175);
PAINT PURPLE (-6775 175);
QUIT
